G04 ================== begin FILE IDENTIFICATION RECORD ==================*
G04 Layout Name:  15669-1.brd*
G04 Film Name:    DP_REF_L1*
G04 File Format:  Gerber RS274X*
G04 File Origin:  Cadence Allegro 16.5-S056*
G04 Origin Date:  Wed Nov 16 04:09:06 2016*
G04 *
G04 Layer:  BOARD GEOMETRY/DP_REF_L1_TBL*
G04 Layer:  BOARD GEOMETRY/DP_REF_L1_TOP*
G04 Layer:  BOARD GEOMETRY/PANEL_OUTLINE*
G04 *
G04 Offset:    (0.00 0.00)*
G04 Mirror:    No*
G04 Mode:      Positive*
G04 Rotation:  0*
G04 FullContactRelief:  No*
G04 UndefLineWidth:     6.00*
G04 ================== end FILE IDENTIFICATION RECORD ====================*
%FSLAX35Y35*MOIN*%
%IR0*IPPOS*OFA0.00000B0.00000*MIA0B0*SFA1.00000B1.00000*%
%ADD10C,.02*%
%ADD11C,.006*%
%ADD12C,.00688*%
G75*
%LPD*%
G75*
G54D10*
G01X1178253Y1853826D02*
X1948253D01*
G01X1178253Y1957776D02*
Y1853826D01*
G01Y1923126D02*
X1948253D01*
G01X1178253Y1888476D02*
X1948253D01*
G01X1178253Y1957776D02*
X1948253D01*
G01X1353253D02*
Y1853826D01*
G01X1633253Y1957776D02*
Y1853826D01*
G01X1738253Y1957776D02*
Y1853826D01*
G01X1948253Y1957776D02*
Y1853826D01*
G54D11*
G01X-84302Y-32800D02*
Y-50300D01*
G01X-89324Y-32800D02*
X-79280D01*
G01X-70514Y-50300D02*
Y-32800D01*
G01Y-41258D02*
X-69422Y-39800D01*
X-68330Y-38925D01*
X-66584Y-38634D01*
X-65274Y-38925D01*
X-63745Y-40092D01*
X-63090Y-41842D01*
Y-50300D01*
G01X-49302Y-38634D02*
Y-50300D01*
G01Y-33967D02*
X-49739Y-33675D01*
Y-33092D01*
X-49302Y-32800D01*
X-48865Y-33092D01*
Y-33675D01*
X-49302Y-33967D01*
G01X-35077Y-48259D02*
X-33985Y-49425D01*
X-32457Y-50300D01*
X-31147D01*
X-29837Y-49717D01*
X-28964Y-48842D01*
X-28527Y-47676D01*
X-28745Y-45925D01*
X-29619Y-45050D01*
X-33549Y-43300D01*
X-34422Y-41258D01*
X-33985Y-39800D01*
X-33112Y-38925D01*
X-31802Y-38634D01*
X-30492Y-38925D01*
X-29182Y-39800D01*
G01X141Y-54675D02*
X1670Y-55842D01*
X3416Y-56133D01*
X4944Y-55842D01*
X6255Y-54384D01*
X7128Y-52342D01*
Y-38634D01*
G01Y-40967D02*
X6255Y-39800D01*
X4944Y-38925D01*
X3416Y-38634D01*
X1670Y-39217D01*
X578Y-40383D01*
X-296Y-42425D01*
X-732Y-44467D01*
X-514Y-46217D01*
X360Y-48259D01*
X1670Y-49717D01*
X3416Y-50300D01*
X4726Y-50008D01*
X6255Y-48842D01*
X7128Y-47676D01*
G01X17423Y-42425D02*
X24410D01*
X23755Y-40383D01*
X22663Y-39217D01*
X21135Y-38634D01*
X19606Y-38925D01*
X18296Y-39800D01*
X17423Y-41842D01*
X16986Y-43592D01*
Y-45342D01*
X17423Y-47092D01*
X18515Y-48842D01*
X19825Y-50008D01*
X21353Y-50300D01*
X22881Y-49717D01*
X24410Y-47967D01*
G01X35141Y-50300D02*
Y-38634D01*
G01Y-40967D02*
X36233Y-39800D01*
X37325Y-38925D01*
X38853Y-38634D01*
X39944Y-38925D01*
X41255Y-39800D01*
G01X51768Y-50300D02*
Y-32800D01*
G01Y-41550D02*
X52860Y-39800D01*
X54170Y-38925D01*
X55480Y-38634D01*
X57444Y-39217D01*
X58755Y-40383D01*
X59628Y-42425D01*
Y-44758D01*
X59191Y-47092D01*
X58318Y-48842D01*
X56790Y-50008D01*
X55480Y-50300D01*
X54170Y-50008D01*
X52860Y-49134D01*
X51768Y-47676D01*
G01X69923Y-42425D02*
X76910D01*
X76255Y-40383D01*
X75163Y-39217D01*
X73635Y-38634D01*
X72106Y-38925D01*
X70796Y-39800D01*
X69923Y-41842D01*
X69486Y-43592D01*
Y-45342D01*
X69923Y-47092D01*
X71015Y-48842D01*
X72325Y-50008D01*
X73853Y-50300D01*
X75381Y-49717D01*
X76910Y-47967D01*
G01X87641Y-50300D02*
Y-38634D01*
G01Y-40967D02*
X88733Y-39800D01*
X89825Y-38925D01*
X91353Y-38634D01*
X92444Y-38925D01*
X93755Y-39800D01*
G01X125698Y-38634D02*
Y-50300D01*
G01Y-33967D02*
X125261Y-33675D01*
Y-33092D01*
X125698Y-32800D01*
X126135Y-33092D01*
Y-33675D01*
X125698Y-33967D01*
G01X139923Y-48259D02*
X141015Y-49425D01*
X142543Y-50300D01*
X143853D01*
X145163Y-49717D01*
X146036Y-48842D01*
X146473Y-47676D01*
X146255Y-45925D01*
X145381Y-45050D01*
X141451Y-43300D01*
X140578Y-41258D01*
X141015Y-39800D01*
X141888Y-38925D01*
X143198Y-38634D01*
X144508Y-38925D01*
X145818Y-39800D01*
G01X174704Y-54675D02*
X176233Y-55842D01*
X177543Y-56133D01*
X179290Y-55550D01*
X180600Y-54092D01*
X181255Y-51466D01*
Y-38634D01*
G01Y-33967D02*
X180818Y-33675D01*
Y-33092D01*
X181255Y-32800D01*
X181691Y-33092D01*
Y-33675D01*
X181255Y-33967D01*
G01X191986Y-38634D02*
Y-46800D01*
X192860Y-48842D01*
X194170Y-50008D01*
X195698Y-50300D01*
X197226Y-50008D01*
X198536Y-48842D01*
X199410Y-46800D01*
G01Y-50300D02*
Y-38634D01*
G01X209923Y-48259D02*
X211015Y-49425D01*
X212543Y-50300D01*
X213853D01*
X215163Y-49717D01*
X216036Y-48842D01*
X216473Y-47676D01*
X216255Y-45925D01*
X215381Y-45050D01*
X211451Y-43300D01*
X210578Y-41258D01*
X211015Y-39800D01*
X211888Y-38925D01*
X213198Y-38634D01*
X214508Y-38925D01*
X215818Y-39800D01*
G01X230698Y-32800D02*
Y-50300D01*
G01X227641Y-38634D02*
X233755D01*
G01X264388Y-50300D02*
Y-35425D01*
X264825Y-33967D01*
X265698Y-33092D01*
X267008Y-32800D01*
X268318Y-33383D01*
X268973Y-34842D01*
G01X266353Y-39800D02*
X261986D01*
G01X283198Y-50300D02*
X281888Y-50008D01*
X280578Y-48842D01*
X279704Y-46800D01*
X279268Y-44467D01*
X279704Y-42133D01*
X280578Y-40092D01*
X281888Y-38925D01*
X283198Y-38634D01*
X284508Y-38925D01*
X285818Y-40092D01*
X286691Y-42133D01*
X286910Y-44467D01*
X286691Y-46800D01*
X285818Y-48842D01*
X284508Y-50008D01*
X283198Y-50300D01*
G01X297641D02*
Y-38634D01*
G01Y-40967D02*
X298733Y-39800D01*
X299825Y-38925D01*
X301353Y-38634D01*
X302444Y-38925D01*
X303755Y-39800D01*
G01X331113Y-55550D02*
X332423Y-56133D01*
X334170Y-55550D01*
X335261Y-54384D01*
X336135Y-52925D01*
X337444Y-48259D01*
X340283Y-38634D01*
G01X333296D02*
X337444Y-48259D01*
G01X353198Y-50300D02*
X351888Y-50008D01*
X350578Y-48842D01*
X349704Y-46800D01*
X349268Y-44467D01*
X349704Y-42133D01*
X350578Y-40092D01*
X351888Y-38925D01*
X353198Y-38634D01*
X354508Y-38925D01*
X355818Y-40092D01*
X356691Y-42133D01*
X356910Y-44467D01*
X356691Y-46800D01*
X355818Y-48842D01*
X354508Y-50008D01*
X353198Y-50300D01*
G01X366986Y-38634D02*
Y-46800D01*
X367860Y-48842D01*
X369170Y-50008D01*
X370698Y-50300D01*
X372226Y-50008D01*
X373536Y-48842D01*
X374410Y-46800D01*
G01Y-50300D02*
Y-38634D01*
G01X385141Y-50300D02*
Y-38634D01*
G01Y-40967D02*
X386233Y-39800D01*
X387325Y-38925D01*
X388853Y-38634D01*
X389944Y-38925D01*
X391255Y-39800D01*
G01X420141Y-50300D02*
Y-38634D01*
G01Y-40967D02*
X421233Y-39800D01*
X422325Y-38925D01*
X423853Y-38634D01*
X424944Y-38925D01*
X426255Y-39800D01*
G01X437423Y-42425D02*
X444410D01*
X443755Y-40383D01*
X442663Y-39217D01*
X441135Y-38634D01*
X439606Y-38925D01*
X438296Y-39800D01*
X437423Y-41842D01*
X436986Y-43592D01*
Y-45342D01*
X437423Y-47092D01*
X438515Y-48842D01*
X439825Y-50008D01*
X441353Y-50300D01*
X442881Y-49717D01*
X444410Y-47967D01*
G01X456888Y-50300D02*
Y-35425D01*
X457325Y-33967D01*
X458198Y-33092D01*
X459508Y-32800D01*
X460818Y-33383D01*
X461473Y-34842D01*
G01X458853Y-39800D02*
X454486D01*
G01X472423Y-42425D02*
X479410D01*
X478755Y-40383D01*
X477663Y-39217D01*
X476135Y-38634D01*
X474606Y-38925D01*
X473296Y-39800D01*
X472423Y-41842D01*
X471986Y-43592D01*
Y-45342D01*
X472423Y-47092D01*
X473515Y-48842D01*
X474825Y-50008D01*
X476353Y-50300D01*
X477881Y-49717D01*
X479410Y-47967D01*
G01X490141Y-50300D02*
Y-38634D01*
G01Y-40967D02*
X491233Y-39800D01*
X492325Y-38925D01*
X493853Y-38634D01*
X494944Y-38925D01*
X496255Y-39800D01*
G01X507423Y-42425D02*
X514410D01*
X513755Y-40383D01*
X512663Y-39217D01*
X511135Y-38634D01*
X509606Y-38925D01*
X508296Y-39800D01*
X507423Y-41842D01*
X506986Y-43592D01*
Y-45342D01*
X507423Y-47092D01*
X508515Y-48842D01*
X509825Y-50008D01*
X511353Y-50300D01*
X512881Y-49717D01*
X514410Y-47967D01*
G01X524486Y-50300D02*
Y-38634D01*
G01Y-41550D02*
X525360Y-40092D01*
X526670Y-38925D01*
X528416Y-38634D01*
X529944Y-38925D01*
X531255Y-40092D01*
X531910Y-42133D01*
Y-50300D01*
G01X549191Y-40092D02*
X547663Y-38925D01*
X546353Y-38634D01*
X544606Y-39217D01*
X543296Y-40383D01*
X542423Y-42425D01*
X542204Y-44467D01*
X542423Y-46509D01*
X543296Y-48259D01*
X544606Y-49717D01*
X546353Y-50300D01*
X547881Y-49717D01*
X549191Y-48550D01*
G01X559923Y-42425D02*
X566910D01*
X566255Y-40383D01*
X565163Y-39217D01*
X563635Y-38634D01*
X562106Y-38925D01*
X560796Y-39800D01*
X559923Y-41842D01*
X559486Y-43592D01*
Y-45342D01*
X559923Y-47092D01*
X561015Y-48842D01*
X562325Y-50008D01*
X563853Y-50300D01*
X565381Y-49717D01*
X566910Y-47967D01*
G01X598198Y-32800D02*
Y-50300D01*
G01X595141Y-38634D02*
X601255D01*
G01X615698Y-50300D02*
X614388Y-50008D01*
X613078Y-48842D01*
X612204Y-46800D01*
X611768Y-44467D01*
X612204Y-42133D01*
X613078Y-40092D01*
X614388Y-38925D01*
X615698Y-38634D01*
X617008Y-38925D01*
X618318Y-40092D01*
X619191Y-42133D01*
X619410Y-44467D01*
X619191Y-46800D01*
X618318Y-48842D01*
X617008Y-50008D01*
X615698Y-50300D01*
G01X649388D02*
Y-35425D01*
X649825Y-33967D01*
X650698Y-33092D01*
X652008Y-32800D01*
X653318Y-33383D01*
X653973Y-34842D01*
G01X651353Y-39800D02*
X646986D01*
G01X668198Y-38634D02*
Y-50300D01*
G01Y-33967D02*
X667761Y-33675D01*
Y-33092D01*
X668198Y-32800D01*
X668635Y-33092D01*
Y-33675D01*
X668198Y-33967D01*
G01X681986Y-50300D02*
Y-38634D01*
G01Y-41550D02*
X682860Y-40092D01*
X684170Y-38925D01*
X685916Y-38634D01*
X687444Y-38925D01*
X688755Y-40092D01*
X689410Y-42133D01*
Y-50300D01*
G01X707128Y-32800D02*
Y-50300D01*
G01Y-47676D02*
X706255Y-49134D01*
X704944Y-50008D01*
X703416Y-50300D01*
X701670Y-49717D01*
X700360Y-48259D01*
X699486Y-46509D01*
X699268Y-44467D01*
X699486Y-42425D01*
X700360Y-40675D01*
X701670Y-39217D01*
X703416Y-38634D01*
X704944Y-38925D01*
X706036Y-39509D01*
X707128Y-40675D01*
G01X738198Y-32800D02*
Y-50300D01*
G01X735141Y-38634D02*
X741255D01*
G01X751986Y-50300D02*
Y-32800D01*
G01Y-41258D02*
X753078Y-39800D01*
X754170Y-38925D01*
X755916Y-38634D01*
X757226Y-38925D01*
X758755Y-40092D01*
X759410Y-41842D01*
Y-50300D01*
G01X769923Y-42425D02*
X776910D01*
X776255Y-40383D01*
X775163Y-39217D01*
X773635Y-38634D01*
X772106Y-38925D01*
X770796Y-39800D01*
X769923Y-41842D01*
X769486Y-43592D01*
Y-45342D01*
X769923Y-47092D01*
X771015Y-48842D01*
X772325Y-50008D01*
X773853Y-50300D01*
X775381Y-49717D01*
X776910Y-47967D01*
G01X803395Y-50300D02*
Y-32800D01*
X807761D01*
X809508Y-33675D01*
X810818Y-34842D01*
X811910Y-36591D01*
X812783Y-38634D01*
X813001Y-41550D01*
X812783Y-44467D01*
X811910Y-46509D01*
X810818Y-48259D01*
X809508Y-49425D01*
X807761Y-50300D01*
X803395D01*
G01X821331D02*
Y-32800D01*
X826571D01*
X828318Y-33675D01*
X829628Y-35717D01*
X830065Y-38050D01*
X829628Y-40383D01*
X828536Y-42133D01*
X826571Y-43009D01*
X821331D01*
G01X860698Y-38634D02*
Y-50300D01*
G01Y-33967D02*
X860261Y-33675D01*
Y-33092D01*
X860698Y-32800D01*
X861135Y-33092D01*
Y-33675D01*
X860698Y-33967D01*
G01X871648Y-50300D02*
Y-38634D01*
G01Y-41842D02*
X872303Y-40383D01*
X873395Y-39217D01*
X874923Y-38634D01*
X876451Y-39217D01*
X877543Y-40383D01*
X878198Y-41842D01*
Y-50300D01*
G01Y-41842D02*
X878853Y-40383D01*
X879944Y-39217D01*
X881473Y-38634D01*
X883001Y-39217D01*
X884093Y-40383D01*
X884748Y-42133D01*
Y-50300D01*
G01X891768Y-56133D02*
Y-38634D01*
G01Y-41258D02*
X892860Y-39800D01*
X893951Y-38925D01*
X895698Y-38634D01*
X897226Y-38925D01*
X898755Y-40383D01*
X899410Y-42425D01*
X899628Y-44467D01*
X899410Y-46509D01*
X898755Y-48550D01*
X897444Y-49717D01*
X895698Y-50300D01*
X894170Y-50008D01*
X892641Y-49134D01*
X891768Y-47967D01*
G01X909923Y-42425D02*
X916910D01*
X916255Y-40383D01*
X915163Y-39217D01*
X913635Y-38634D01*
X912106Y-38925D01*
X910796Y-39800D01*
X909923Y-41842D01*
X909486Y-43592D01*
Y-45342D01*
X909923Y-47092D01*
X911015Y-48842D01*
X912325Y-50008D01*
X913853Y-50300D01*
X915381Y-49717D01*
X916910Y-47967D01*
G01X934628Y-32800D02*
Y-50300D01*
G01Y-47676D02*
X933755Y-49134D01*
X932444Y-50008D01*
X930916Y-50300D01*
X929170Y-49717D01*
X927860Y-48259D01*
X926986Y-46509D01*
X926768Y-44467D01*
X926986Y-42425D01*
X927860Y-40675D01*
X929170Y-39217D01*
X930916Y-38634D01*
X932444Y-38925D01*
X933536Y-39509D01*
X934628Y-40675D01*
G01X952128Y-50300D02*
Y-38634D01*
G01Y-40675D02*
X951255Y-39509D01*
X949944Y-38925D01*
X948416Y-38634D01*
X946888Y-39217D01*
X945578Y-40383D01*
X944704Y-42133D01*
X944268Y-44467D01*
X944704Y-46800D01*
X945578Y-48550D01*
X946888Y-49717D01*
X948416Y-50300D01*
X949944Y-50008D01*
X951255Y-49134D01*
X952128Y-47967D01*
G01X961986Y-50300D02*
Y-38634D01*
G01Y-41550D02*
X962860Y-40092D01*
X964170Y-38925D01*
X965916Y-38634D01*
X967444Y-38925D01*
X968755Y-40092D01*
X969410Y-42133D01*
Y-50300D01*
G01X986691Y-40092D02*
X985163Y-38925D01*
X983853Y-38634D01*
X982106Y-39217D01*
X980796Y-40383D01*
X979923Y-42425D01*
X979704Y-44467D01*
X979923Y-46509D01*
X980796Y-48259D01*
X982106Y-49717D01*
X983853Y-50300D01*
X985381Y-49717D01*
X986691Y-48550D01*
G01X997423Y-42425D02*
X1004410D01*
X1003755Y-40383D01*
X1002663Y-39217D01*
X1001135Y-38634D01*
X999606Y-38925D01*
X998296Y-39800D01*
X997423Y-41842D01*
X996986Y-43592D01*
Y-45342D01*
X997423Y-47092D01*
X998515Y-48842D01*
X999825Y-50008D01*
X1001353Y-50300D01*
X1002881Y-49717D01*
X1004410Y-47967D01*
G01X1035698Y-32800D02*
Y-50300D01*
G01X1032641Y-38634D02*
X1038755D01*
G01X1050141Y-50300D02*
Y-38634D01*
G01Y-40967D02*
X1051233Y-39800D01*
X1052325Y-38925D01*
X1053853Y-38634D01*
X1054944Y-38925D01*
X1056255Y-39800D01*
G01X1074628Y-50300D02*
Y-38634D01*
G01Y-40675D02*
X1073755Y-39509D01*
X1072444Y-38925D01*
X1070916Y-38634D01*
X1069388Y-39217D01*
X1068078Y-40383D01*
X1067204Y-42133D01*
X1066768Y-44467D01*
X1067204Y-46800D01*
X1068078Y-48550D01*
X1069388Y-49717D01*
X1070916Y-50300D01*
X1072444Y-50008D01*
X1073755Y-49134D01*
X1074628Y-47967D01*
G01X1091691Y-40092D02*
X1090163Y-38925D01*
X1088853Y-38634D01*
X1087106Y-39217D01*
X1085796Y-40383D01*
X1084923Y-42425D01*
X1084704Y-44467D01*
X1084923Y-46509D01*
X1085796Y-48259D01*
X1087106Y-49717D01*
X1088853Y-50300D01*
X1090381Y-49717D01*
X1091691Y-48550D01*
G01X1102423Y-42425D02*
X1109410D01*
X1108755Y-40383D01*
X1107663Y-39217D01*
X1106135Y-38634D01*
X1104606Y-38925D01*
X1103296Y-39800D01*
X1102423Y-41842D01*
X1101986Y-43592D01*
Y-45342D01*
X1102423Y-47092D01*
X1103515Y-48842D01*
X1104825Y-50008D01*
X1106353Y-50300D01*
X1107881Y-49717D01*
X1109410Y-47967D01*
G01X1119923Y-48259D02*
X1121015Y-49425D01*
X1122543Y-50300D01*
X1123853D01*
X1125163Y-49717D01*
X1126036Y-48842D01*
X1126473Y-47676D01*
X1126255Y-45925D01*
X1125381Y-45050D01*
X1121451Y-43300D01*
X1120578Y-41258D01*
X1121015Y-39800D01*
X1121888Y-38925D01*
X1123198Y-38634D01*
X1124508Y-38925D01*
X1125818Y-39800D01*
G01X1158198Y-38634D02*
Y-50300D01*
G01Y-33967D02*
X1157761Y-33675D01*
Y-33092D01*
X1158198Y-32800D01*
X1158635Y-33092D01*
Y-33675D01*
X1158198Y-33967D01*
G01X1171986Y-50300D02*
Y-38634D01*
G01Y-41550D02*
X1172860Y-40092D01*
X1174170Y-38925D01*
X1175916Y-38634D01*
X1177444Y-38925D01*
X1178755Y-40092D01*
X1179410Y-42133D01*
Y-50300D01*
G01X1210698D02*
Y-32800D01*
G01X1232128Y-50300D02*
Y-38634D01*
G01Y-40675D02*
X1231255Y-39509D01*
X1229944Y-38925D01*
X1228416Y-38634D01*
X1226888Y-39217D01*
X1225578Y-40383D01*
X1224704Y-42133D01*
X1224268Y-44467D01*
X1224704Y-46800D01*
X1225578Y-48550D01*
X1226888Y-49717D01*
X1228416Y-50300D01*
X1229944Y-50008D01*
X1231255Y-49134D01*
X1232128Y-47967D01*
G01X1241113Y-55550D02*
X1242423Y-56133D01*
X1244170Y-55550D01*
X1245261Y-54384D01*
X1246135Y-52925D01*
X1247444Y-48259D01*
X1250283Y-38634D01*
G01X1243296D02*
X1247444Y-48259D01*
G01X1259923Y-42425D02*
X1266910D01*
X1266255Y-40383D01*
X1265163Y-39217D01*
X1263635Y-38634D01*
X1262106Y-38925D01*
X1260796Y-39800D01*
X1259923Y-41842D01*
X1259486Y-43592D01*
Y-45342D01*
X1259923Y-47092D01*
X1261015Y-48842D01*
X1262325Y-50008D01*
X1263853Y-50300D01*
X1265381Y-49717D01*
X1266910Y-47967D01*
G01X1277641Y-50300D02*
Y-38634D01*
G01Y-40967D02*
X1278733Y-39800D01*
X1279825Y-38925D01*
X1281353Y-38634D01*
X1282444Y-38925D01*
X1283755Y-39800D01*
G01X1311331Y-32800D02*
Y-50300D01*
X1320065D01*
G01X1333198D02*
Y-32800D01*
X1330578Y-36300D01*
G01Y-50300D02*
X1335818D01*
G01X1350698Y-50883D02*
X1350261Y-50592D01*
Y-50008D01*
X1350698Y-49717D01*
X1351135Y-50008D01*
Y-50592D01*
X1350698Y-50883D01*
G01X1201883Y1950376D02*
X1207123D01*
G01X1204503D02*
Y1932876D01*
G01X1201883D02*
X1207123D01*
G01X1216326D02*
Y1950376D01*
X1222003Y1935793D01*
X1227680Y1950376D01*
Y1932876D01*
G01X1235136D02*
Y1950376D01*
X1240376D01*
X1242123Y1949501D01*
X1243433Y1947459D01*
X1243870Y1945126D01*
X1243433Y1942793D01*
X1242341Y1941043D01*
X1240376Y1940167D01*
X1235136D01*
G01X1255911Y1927043D02*
X1253728Y1929959D01*
X1252636Y1932876D01*
Y1944542D01*
X1253728Y1947459D01*
X1255911Y1950376D01*
G01X1274503Y1932876D02*
X1272756Y1933168D01*
X1271228Y1934334D01*
X1269918Y1936084D01*
X1269044Y1938126D01*
X1268608Y1940459D01*
Y1942793D01*
X1269044Y1945126D01*
X1269918Y1947168D01*
X1271228Y1948917D01*
X1272756Y1950084D01*
X1274503Y1950376D01*
X1276249Y1950084D01*
X1277778Y1948917D01*
X1279088Y1947168D01*
X1279962Y1945126D01*
X1280398Y1942793D01*
Y1940459D01*
X1279962Y1938126D01*
X1279088Y1936084D01*
X1277778Y1934334D01*
X1276249Y1933168D01*
X1274503Y1932876D01*
G01X1288291D02*
Y1950376D01*
G01Y1941918D02*
X1289383Y1943376D01*
X1290475Y1944251D01*
X1292221Y1944542D01*
X1293531Y1944251D01*
X1295060Y1943084D01*
X1295715Y1941334D01*
Y1932876D01*
G01X1302953D02*
Y1944542D01*
G01Y1941334D02*
X1303608Y1942793D01*
X1304700Y1943959D01*
X1306228Y1944542D01*
X1307756Y1943959D01*
X1308848Y1942793D01*
X1309503Y1941334D01*
Y1932876D01*
G01Y1941334D02*
X1310158Y1942793D01*
X1311249Y1943959D01*
X1312778Y1944542D01*
X1314306Y1943959D01*
X1315398Y1942793D01*
X1316053Y1941043D01*
Y1932876D01*
G01X1328095Y1927043D02*
X1330278Y1929959D01*
X1331370Y1932876D01*
Y1944542D01*
X1330278Y1947459D01*
X1328095Y1950376D01*
G01X1180000Y1967526D02*
Y1985026D01*
X1184366D01*
X1186113Y1984151D01*
X1187423Y1982984D01*
X1188515Y1981235D01*
X1189388Y1979192D01*
X1189606Y1976276D01*
X1189388Y1973359D01*
X1188515Y1971317D01*
X1187423Y1969567D01*
X1186113Y1968401D01*
X1184366Y1967526D01*
X1180000D01*
G01X1197936D02*
Y1985026D01*
X1203176D01*
X1204923Y1984151D01*
X1206233Y1982109D01*
X1206670Y1979776D01*
X1206233Y1977443D01*
X1205141Y1975693D01*
X1203176Y1974817D01*
X1197936D01*
G01X1234683Y1985026D02*
X1239923D01*
G01X1237303D02*
Y1967526D01*
G01X1234683D02*
X1239923D01*
G01X1249126D02*
Y1985026D01*
X1254803Y1970443D01*
X1260480Y1985026D01*
Y1967526D01*
G01X1267936D02*
Y1985026D01*
X1273176D01*
X1274923Y1984151D01*
X1276233Y1982109D01*
X1276670Y1979776D01*
X1276233Y1977443D01*
X1275141Y1975693D01*
X1273176Y1974817D01*
X1267936D01*
G01X1294170Y1967526D02*
X1285436D01*
Y1985026D01*
X1294170D01*
G01X1290676Y1976568D02*
X1285436D01*
G01X1302500Y1967526D02*
Y1985026D01*
X1306866D01*
X1308613Y1984151D01*
X1309923Y1982984D01*
X1311015Y1981235D01*
X1311888Y1979192D01*
X1312106Y1976276D01*
X1311888Y1973359D01*
X1311015Y1971317D01*
X1309923Y1969567D01*
X1308613Y1968401D01*
X1306866Y1967526D01*
X1302500D01*
G01X1319344D02*
X1324803Y1985026D01*
X1330262Y1967526D01*
G01X1328296Y1973651D02*
X1321309D01*
G01X1337281Y1967526D02*
Y1985026D01*
X1347325Y1967526D01*
Y1985026D01*
G01X1364606Y1983567D02*
X1363296Y1984443D01*
X1361768Y1985026D01*
X1360021D01*
X1358056Y1984151D01*
X1356528Y1982693D01*
X1355436Y1980942D01*
X1354563Y1978026D01*
X1354344Y1975401D01*
X1354781Y1972776D01*
X1355436Y1971026D01*
X1356746Y1969276D01*
X1358275Y1968109D01*
X1359803Y1967526D01*
X1361331D01*
X1362860Y1968109D01*
X1364170Y1968984D01*
X1365262Y1970150D01*
G01X1381670Y1967526D02*
X1372936D01*
Y1985026D01*
X1381670D01*
G01X1378176Y1976568D02*
X1372936D01*
G01X1412303Y1985026D02*
Y1967526D01*
G01X1407281Y1985026D02*
X1417325D01*
G01X1424344Y1967526D02*
X1429803Y1985026D01*
X1435262Y1967526D01*
G01X1433296Y1973651D02*
X1426309D01*
G01X1449049Y1976859D02*
X1449923Y1977734D01*
X1450578Y1979192D01*
X1451015Y1981235D01*
X1450578Y1982984D01*
X1449705Y1984151D01*
X1448176Y1985026D01*
X1442281D01*
Y1967526D01*
X1449486D01*
X1451015Y1968692D01*
X1451888Y1970443D01*
X1452325Y1972484D01*
X1451888Y1974526D01*
X1450578Y1976276D01*
X1449049Y1976859D01*
X1442281D01*
G01X1460436Y1985026D02*
Y1967526D01*
X1469170D01*
G01X1486670D02*
X1477936D01*
Y1985026D01*
X1486670D01*
G01X1483176Y1976568D02*
X1477936D01*
G01X1499803Y1966943D02*
X1499366Y1967234D01*
Y1967818D01*
X1499803Y1968109D01*
X1500240Y1967818D01*
Y1967234D01*
X1499803Y1966943D01*
G01Y1974817D02*
X1499366Y1975109D01*
Y1975693D01*
X1499803Y1975984D01*
X1500240Y1975693D01*
Y1975109D01*
X1499803Y1974817D01*
G01X1530436Y1985026D02*
Y1967526D01*
X1539170D01*
G01X1552303D02*
Y1985026D01*
X1549683Y1981526D01*
G01Y1967526D02*
X1554923D01*
G01X1217200Y1862993D02*
X1226806Y1875826D01*
G01X1222003Y1878159D02*
Y1860659D01*
G01X1226806Y1862993D02*
X1217200Y1875826D01*
G01X1215453Y1869409D02*
X1228553D01*
G01X1239503Y1863576D02*
Y1881076D01*
X1236883Y1877576D01*
G01Y1863576D02*
X1242123D01*
G01X1257003Y1881076D02*
X1255256Y1880493D01*
X1253946Y1879034D01*
X1253073Y1877285D01*
X1252418Y1874951D01*
X1252200Y1872326D01*
X1252418Y1869701D01*
X1253073Y1867367D01*
X1253946Y1865617D01*
X1255256Y1864159D01*
X1257003Y1863576D01*
X1258749Y1864159D01*
X1260060Y1865617D01*
X1260933Y1867367D01*
X1261588Y1869701D01*
X1261806Y1872326D01*
X1261588Y1874951D01*
X1260933Y1877285D01*
X1260060Y1879034D01*
X1258749Y1880493D01*
X1257003Y1881076D01*
G01X1274503D02*
X1272756Y1880493D01*
X1271446Y1879034D01*
X1270573Y1877285D01*
X1269918Y1874951D01*
X1269700Y1872326D01*
X1269918Y1869701D01*
X1270573Y1867367D01*
X1271446Y1865617D01*
X1272756Y1864159D01*
X1274503Y1863576D01*
X1276249Y1864159D01*
X1277560Y1865617D01*
X1278433Y1867367D01*
X1279088Y1869701D01*
X1279306Y1872326D01*
X1279088Y1874951D01*
X1278433Y1877285D01*
X1277560Y1879034D01*
X1276249Y1880493D01*
X1274503Y1881076D01*
G01X1292003Y1862993D02*
X1291566Y1863284D01*
Y1863868D01*
X1292003Y1864159D01*
X1292440Y1863868D01*
Y1863284D01*
X1292003Y1862993D01*
G01X1309503Y1881076D02*
X1307756Y1880493D01*
X1306446Y1879034D01*
X1305573Y1877285D01*
X1304918Y1874951D01*
X1304700Y1872326D01*
X1304918Y1869701D01*
X1305573Y1867367D01*
X1306446Y1865617D01*
X1307756Y1864159D01*
X1309503Y1863576D01*
X1311249Y1864159D01*
X1312560Y1865617D01*
X1313433Y1867367D01*
X1314088Y1869701D01*
X1314306Y1872326D01*
X1314088Y1874951D01*
X1313433Y1877285D01*
X1312560Y1879034D01*
X1311249Y1880493D01*
X1309503Y1881076D01*
G01X1239503Y1898226D02*
X1241031Y1898518D01*
X1242778Y1899392D01*
X1243870Y1900850D01*
X1244306Y1902893D01*
X1243870Y1904934D01*
X1242560Y1906684D01*
X1240595Y1907559D01*
X1238411D01*
X1237101Y1908143D01*
X1236009Y1909601D01*
X1235573Y1911642D01*
X1236228Y1913684D01*
X1237756Y1915143D01*
X1239503Y1915726D01*
X1241249Y1915143D01*
X1242778Y1913684D01*
X1243433Y1911642D01*
X1242996Y1909601D01*
X1241905Y1908143D01*
X1240595Y1907559D01*
X1238411D01*
X1236446Y1906684D01*
X1235136Y1904934D01*
X1234700Y1902893D01*
X1235136Y1900850D01*
X1236228Y1899392D01*
X1237975Y1898518D01*
X1239503Y1898226D01*
G01X1252200Y1900850D02*
X1253509Y1899392D01*
X1255038Y1898518D01*
X1257003Y1898226D01*
X1258968Y1898809D01*
X1260496Y1899976D01*
X1261588Y1902017D01*
X1261806Y1904351D01*
X1261370Y1906684D01*
X1260278Y1908143D01*
X1258749Y1909309D01*
X1257221Y1909601D01*
X1255693Y1909309D01*
X1253728Y1908143D01*
X1254383Y1915726D01*
X1260278D01*
G01X1274503Y1897643D02*
X1274066Y1897934D01*
Y1898518D01*
X1274503Y1898809D01*
X1274940Y1898518D01*
Y1897934D01*
X1274503Y1897643D01*
G01X1292003Y1915726D02*
X1290256Y1915143D01*
X1288946Y1913684D01*
X1288073Y1911935D01*
X1287418Y1909601D01*
X1287200Y1906976D01*
X1287418Y1904351D01*
X1288073Y1902017D01*
X1288946Y1900267D01*
X1290256Y1898809D01*
X1292003Y1898226D01*
X1293749Y1898809D01*
X1295060Y1900267D01*
X1295933Y1902017D01*
X1296588Y1904351D01*
X1296806Y1906976D01*
X1296588Y1909601D01*
X1295933Y1911935D01*
X1295060Y1913684D01*
X1293749Y1915143D01*
X1292003Y1915726D01*
G01X1399203Y1950376D02*
X1402259Y1932876D01*
X1405753Y1950376D01*
X1409246Y1932876D01*
X1412303Y1950376D01*
G01X1420633D02*
X1425873D01*
G01X1423253D02*
Y1932876D01*
G01X1420633D02*
X1425873D01*
G01X1435950D02*
Y1950376D01*
X1440316D01*
X1442063Y1949501D01*
X1443373Y1948334D01*
X1444465Y1946585D01*
X1445338Y1944542D01*
X1445556Y1941626D01*
X1445338Y1938709D01*
X1444465Y1936667D01*
X1443373Y1934917D01*
X1442063Y1933751D01*
X1440316Y1932876D01*
X1435950D01*
G01X1458253Y1950376D02*
Y1932876D01*
G01X1453231Y1950376D02*
X1463275D01*
G01X1471168Y1932876D02*
Y1950376D01*
G01X1480338D02*
Y1932876D01*
G01Y1941626D02*
X1471168D01*
G01X1492161Y1927043D02*
X1489978Y1929959D01*
X1488886Y1932876D01*
Y1944542D01*
X1489978Y1947459D01*
X1492161Y1950376D01*
G01X1504203Y1932876D02*
Y1944542D01*
G01Y1941334D02*
X1504858Y1942793D01*
X1505950Y1943959D01*
X1507478Y1944542D01*
X1509006Y1943959D01*
X1510098Y1942793D01*
X1510753Y1941334D01*
Y1932876D01*
G01Y1941334D02*
X1511408Y1942793D01*
X1512499Y1943959D01*
X1514028Y1944542D01*
X1515556Y1943959D01*
X1516648Y1942793D01*
X1517303Y1941043D01*
Y1932876D01*
G01X1528253Y1944542D02*
Y1932876D01*
G01Y1949209D02*
X1527816Y1949501D01*
Y1950084D01*
X1528253Y1950376D01*
X1528690Y1950084D01*
Y1949501D01*
X1528253Y1949209D01*
G01X1545753Y1932876D02*
Y1950376D01*
G01X1559978Y1934917D02*
X1561070Y1933751D01*
X1562598Y1932876D01*
X1563908D01*
X1565218Y1933459D01*
X1566091Y1934334D01*
X1566528Y1935500D01*
X1566310Y1937251D01*
X1565436Y1938126D01*
X1561506Y1939876D01*
X1560633Y1941918D01*
X1561070Y1943376D01*
X1561943Y1944251D01*
X1563253Y1944542D01*
X1564563Y1944251D01*
X1565873Y1943376D01*
G01X1581845Y1927043D02*
X1584028Y1929959D01*
X1585120Y1932876D01*
Y1944542D01*
X1584028Y1947459D01*
X1581845Y1950376D01*
G01X1419105Y1905517D02*
X1420633Y1907559D01*
X1421943Y1908726D01*
X1423690Y1909309D01*
X1425218Y1908726D01*
X1426310Y1907559D01*
X1427183Y1905809D01*
X1427401Y1903768D01*
X1427183Y1902017D01*
X1426310Y1900267D01*
X1424999Y1898809D01*
X1423471Y1898226D01*
X1421725Y1898809D01*
X1420196Y1900559D01*
X1419323Y1903184D01*
X1419105Y1906101D01*
X1419541Y1909892D01*
X1420196Y1911935D01*
X1421288Y1913976D01*
X1422816Y1915434D01*
X1424345Y1915726D01*
X1425873Y1915143D01*
X1426965Y1913684D01*
G01X1440753Y1897643D02*
X1440316Y1897934D01*
Y1898518D01*
X1440753Y1898809D01*
X1441190Y1898518D01*
Y1897934D01*
X1440753Y1897643D01*
G01X1458253Y1898226D02*
X1459781Y1898518D01*
X1461528Y1899392D01*
X1462620Y1900850D01*
X1463056Y1902893D01*
X1462620Y1904934D01*
X1461310Y1906684D01*
X1459345Y1907559D01*
X1457161D01*
X1455851Y1908143D01*
X1454759Y1909601D01*
X1454323Y1911642D01*
X1454978Y1913684D01*
X1456506Y1915143D01*
X1458253Y1915726D01*
X1459999Y1915143D01*
X1461528Y1913684D01*
X1462183Y1911642D01*
X1461746Y1909601D01*
X1460655Y1908143D01*
X1459345Y1907559D01*
X1457161D01*
X1455196Y1906684D01*
X1453886Y1904934D01*
X1453450Y1902893D01*
X1453886Y1900850D01*
X1454978Y1899392D01*
X1456725Y1898518D01*
X1458253Y1898226D01*
G01X1475753D02*
X1477281Y1898518D01*
X1479028Y1899392D01*
X1480120Y1900850D01*
X1480556Y1902893D01*
X1480120Y1904934D01*
X1478810Y1906684D01*
X1476845Y1907559D01*
X1474661D01*
X1473351Y1908143D01*
X1472259Y1909601D01*
X1471823Y1911642D01*
X1472478Y1913684D01*
X1474006Y1915143D01*
X1475753Y1915726D01*
X1477499Y1915143D01*
X1479028Y1913684D01*
X1479683Y1911642D01*
X1479246Y1909601D01*
X1478155Y1908143D01*
X1476845Y1907559D01*
X1474661D01*
X1472696Y1906684D01*
X1471386Y1904934D01*
X1470950Y1902893D01*
X1471386Y1900850D01*
X1472478Y1899392D01*
X1474225Y1898518D01*
X1475753Y1898226D01*
G01X1489323Y1897643D02*
X1497183Y1915726D01*
G01X1505950Y1900850D02*
X1507259Y1899392D01*
X1508788Y1898518D01*
X1510753Y1898226D01*
X1512718Y1898809D01*
X1514246Y1899976D01*
X1515338Y1902017D01*
X1515556Y1904351D01*
X1515120Y1906684D01*
X1514028Y1908143D01*
X1512499Y1909309D01*
X1510971Y1909601D01*
X1509443Y1909309D01*
X1507478Y1908143D01*
X1508133Y1915726D01*
X1514028D01*
G01X1528253Y1897643D02*
X1527816Y1897934D01*
Y1898518D01*
X1528253Y1898809D01*
X1528690Y1898518D01*
Y1897934D01*
X1528253Y1897643D01*
G01X1545753Y1898226D02*
Y1915726D01*
X1543133Y1912226D01*
G01Y1898226D02*
X1548373D01*
G01X1558450Y1901726D02*
X1559759Y1899684D01*
X1561506Y1898518D01*
X1563471Y1898226D01*
X1565218Y1898518D01*
X1566965Y1899976D01*
X1568056Y1901726D01*
X1568275Y1903476D01*
X1567838Y1905517D01*
X1566310Y1906976D01*
X1564781Y1907559D01*
X1562816D01*
G01X1564781D02*
X1566091Y1908434D01*
X1567183Y1909892D01*
X1567620Y1911642D01*
X1567183Y1913393D01*
X1566091Y1914851D01*
X1564126Y1915726D01*
X1562161Y1915434D01*
X1560196Y1914267D01*
G01X1435950Y1866200D02*
X1437259Y1864742D01*
X1438788Y1863868D01*
X1440753Y1863576D01*
X1442718Y1864159D01*
X1444246Y1865326D01*
X1445338Y1867367D01*
X1445556Y1869701D01*
X1445120Y1872034D01*
X1444028Y1873493D01*
X1442499Y1874659D01*
X1440971Y1874951D01*
X1439443Y1874659D01*
X1437478Y1873493D01*
X1438133Y1881076D01*
X1444028D01*
G01X1458253Y1862993D02*
X1457816Y1863284D01*
Y1863868D01*
X1458253Y1864159D01*
X1458690Y1863868D01*
Y1863284D01*
X1458253Y1862993D01*
G01X1475753Y1881076D02*
X1474006Y1880493D01*
X1472696Y1879034D01*
X1471823Y1877285D01*
X1471168Y1874951D01*
X1470950Y1872326D01*
X1471168Y1869701D01*
X1471823Y1867367D01*
X1472696Y1865617D01*
X1474006Y1864159D01*
X1475753Y1863576D01*
X1477499Y1864159D01*
X1478810Y1865617D01*
X1479683Y1867367D01*
X1480338Y1869701D01*
X1480556Y1872326D01*
X1480338Y1874951D01*
X1479683Y1877285D01*
X1478810Y1879034D01*
X1477499Y1880493D01*
X1475753Y1881076D01*
G01X1489323Y1862993D02*
X1497183Y1881076D01*
G01X1506605Y1870867D02*
X1508133Y1872909D01*
X1509443Y1874076D01*
X1511190Y1874659D01*
X1512718Y1874076D01*
X1513810Y1872909D01*
X1514683Y1871159D01*
X1514901Y1869118D01*
X1514683Y1867367D01*
X1513810Y1865617D01*
X1512499Y1864159D01*
X1510971Y1863576D01*
X1509225Y1864159D01*
X1507696Y1865909D01*
X1506823Y1868534D01*
X1506605Y1871451D01*
X1507041Y1875242D01*
X1507696Y1877285D01*
X1508788Y1879326D01*
X1510316Y1880784D01*
X1511845Y1881076D01*
X1513373Y1880493D01*
X1514465Y1879034D01*
G01X1528253Y1862993D02*
X1527816Y1863284D01*
Y1863868D01*
X1528253Y1864159D01*
X1528690Y1863868D01*
Y1863284D01*
X1528253Y1862993D01*
G01X1545753Y1881076D02*
X1544006Y1880493D01*
X1542696Y1879034D01*
X1541823Y1877285D01*
X1541168Y1874951D01*
X1540950Y1872326D01*
X1541168Y1869701D01*
X1541823Y1867367D01*
X1542696Y1865617D01*
X1544006Y1864159D01*
X1545753Y1863576D01*
X1547499Y1864159D01*
X1548810Y1865617D01*
X1549683Y1867367D01*
X1550338Y1869701D01*
X1550556Y1872326D01*
X1550338Y1874951D01*
X1549683Y1877285D01*
X1548810Y1879034D01*
X1547499Y1880493D01*
X1545753Y1881076D01*
G01X1672200Y1863576D02*
Y1881076D01*
X1676566D01*
X1678313Y1880201D01*
X1679623Y1879034D01*
X1680715Y1877285D01*
X1681588Y1875242D01*
X1681806Y1872326D01*
X1681588Y1869409D01*
X1680715Y1867367D01*
X1679623Y1865617D01*
X1678313Y1864451D01*
X1676566Y1863576D01*
X1672200D01*
G01X1690136D02*
Y1881076D01*
X1695376D01*
X1697123Y1880201D01*
X1698433Y1878159D01*
X1698870Y1875826D01*
X1698433Y1873493D01*
X1697341Y1871743D01*
X1695376Y1870867D01*
X1690136D01*
G01X1659503Y1950376D02*
Y1932876D01*
G01X1654481Y1950376D02*
X1664525D01*
G01X1677003Y1932876D02*
Y1940751D01*
X1672636Y1950376D01*
G01X1681370D02*
X1677003Y1940751D01*
G01X1690136Y1932876D02*
Y1950376D01*
X1695376D01*
X1697123Y1949501D01*
X1698433Y1947459D01*
X1698870Y1945126D01*
X1698433Y1942793D01*
X1697341Y1941043D01*
X1695376Y1940167D01*
X1690136D01*
G01X1716370Y1932876D02*
X1707636D01*
Y1950376D01*
X1716370D01*
G01X1712876Y1941918D02*
X1707636D01*
G01X1672200Y1898226D02*
Y1915726D01*
X1676566D01*
X1678313Y1914851D01*
X1679623Y1913684D01*
X1680715Y1911935D01*
X1681588Y1909892D01*
X1681806Y1906976D01*
X1681588Y1904059D01*
X1680715Y1902017D01*
X1679623Y1900267D01*
X1678313Y1899101D01*
X1676566Y1898226D01*
X1672200D01*
G01X1690136D02*
Y1915726D01*
X1695376D01*
X1697123Y1914851D01*
X1698433Y1912809D01*
X1698870Y1910476D01*
X1698433Y1908143D01*
X1697341Y1906393D01*
X1695376Y1905517D01*
X1690136D01*
G01X1760136Y1932876D02*
Y1950376D01*
X1765595D01*
X1767341Y1949501D01*
X1768433Y1948334D01*
X1768870Y1946001D01*
X1768433Y1943667D01*
X1767123Y1942209D01*
X1765595Y1941334D01*
X1760136D01*
G01X1765595D02*
X1768870Y1932876D01*
G01X1778728Y1940751D02*
X1785715D01*
X1785060Y1942793D01*
X1783968Y1943959D01*
X1782440Y1944542D01*
X1780911Y1944251D01*
X1779601Y1943376D01*
X1778728Y1941334D01*
X1778291Y1939584D01*
Y1937834D01*
X1778728Y1936084D01*
X1779820Y1934334D01*
X1781130Y1933168D01*
X1782658Y1932876D01*
X1784186Y1933459D01*
X1785715Y1935209D01*
G01X1798193Y1932876D02*
Y1947751D01*
X1798630Y1949209D01*
X1799503Y1950084D01*
X1800813Y1950376D01*
X1802123Y1949793D01*
X1802778Y1948334D01*
G01X1800158Y1943376D02*
X1795791D01*
G01X1817003Y1932293D02*
X1816566Y1932584D01*
Y1933168D01*
X1817003Y1933459D01*
X1817440Y1933168D01*
Y1932584D01*
X1817003Y1932293D01*
G01X1847636Y1932876D02*
Y1950376D01*
X1852876D01*
X1854623Y1949501D01*
X1855933Y1947459D01*
X1856370Y1945126D01*
X1855933Y1942793D01*
X1854841Y1941043D01*
X1852876Y1940167D01*
X1847636D01*
G01X1869503Y1932876D02*
Y1950376D01*
G01X1890933Y1932876D02*
Y1944542D01*
G01Y1942501D02*
X1890060Y1943667D01*
X1888749Y1944251D01*
X1887221Y1944542D01*
X1885693Y1943959D01*
X1884383Y1942793D01*
X1883509Y1941043D01*
X1883073Y1938709D01*
X1883509Y1936376D01*
X1884383Y1934626D01*
X1885693Y1933459D01*
X1887221Y1932876D01*
X1888749Y1933168D01*
X1890060Y1934042D01*
X1890933Y1935209D01*
G01X1900791Y1932876D02*
Y1944542D01*
G01Y1941626D02*
X1901665Y1943084D01*
X1902975Y1944251D01*
X1904721Y1944542D01*
X1906249Y1944251D01*
X1907560Y1943084D01*
X1908215Y1941043D01*
Y1932876D01*
G01X1918728Y1940751D02*
X1925715D01*
X1925060Y1942793D01*
X1923968Y1943959D01*
X1922440Y1944542D01*
X1920911Y1944251D01*
X1919601Y1943376D01*
X1918728Y1941334D01*
X1918291Y1939584D01*
Y1937834D01*
X1918728Y1936084D01*
X1919820Y1934334D01*
X1921130Y1933168D01*
X1922658Y1932876D01*
X1924186Y1933459D01*
X1925715Y1935209D01*
G01X1830136Y1881076D02*
Y1863576D01*
X1838870D01*
G01X1847855Y1878159D02*
X1849165Y1879909D01*
X1850693Y1880784D01*
X1852440Y1881076D01*
X1854623Y1880493D01*
X1856151Y1879034D01*
X1856588Y1877285D01*
X1856370Y1875534D01*
X1855496Y1874076D01*
X1851130Y1871159D01*
X1849165Y1869118D01*
X1847855Y1866200D01*
X1847418Y1863576D01*
X1856588D01*
G01X1830136Y1915726D02*
Y1898226D01*
X1838870D01*
G01X1847855Y1912809D02*
X1849165Y1914559D01*
X1850693Y1915434D01*
X1852440Y1915726D01*
X1854623Y1915143D01*
X1856151Y1913684D01*
X1856588Y1911935D01*
X1856370Y1910184D01*
X1855496Y1908726D01*
X1851130Y1905809D01*
X1849165Y1903768D01*
X1847855Y1900850D01*
X1847418Y1898226D01*
X1856588D01*
G01X1965000Y1932293D02*
X1974606Y1945126D01*
G01X1969803Y1947459D02*
Y1929959D01*
G01X1974606Y1932293D02*
X1965000Y1945126D01*
G01X1963253Y1938709D02*
X1976353D01*
G01X2001965D02*
X2007641D01*
G01X2035000Y1932876D02*
Y1950376D01*
X2039366D01*
X2041113Y1949501D01*
X2042423Y1948334D01*
X2043515Y1946585D01*
X2044388Y1944542D01*
X2044606Y1941626D01*
X2044388Y1938709D01*
X2043515Y1936667D01*
X2042423Y1934917D01*
X2041113Y1933751D01*
X2039366Y1932876D01*
X2035000D01*
G01X2054028Y1940751D02*
X2061015D01*
X2060360Y1942793D01*
X2059268Y1943959D01*
X2057740Y1944542D01*
X2056211Y1944251D01*
X2054901Y1943376D01*
X2054028Y1941334D01*
X2053591Y1939584D01*
Y1937834D01*
X2054028Y1936084D01*
X2055120Y1934334D01*
X2056430Y1933168D01*
X2057958Y1932876D01*
X2059486Y1933459D01*
X2061015Y1935209D01*
G01X2071091Y1932876D02*
Y1944542D01*
G01Y1941626D02*
X2071965Y1943084D01*
X2073275Y1944251D01*
X2075021Y1944542D01*
X2076549Y1944251D01*
X2077860Y1943084D01*
X2078515Y1941043D01*
Y1932876D01*
G01X2092303D02*
X2090993Y1933168D01*
X2089683Y1934334D01*
X2088809Y1936376D01*
X2088373Y1938709D01*
X2088809Y1941043D01*
X2089683Y1943084D01*
X2090993Y1944251D01*
X2092303Y1944542D01*
X2093613Y1944251D01*
X2094923Y1943084D01*
X2095796Y1941043D01*
X2096015Y1938709D01*
X2095796Y1936376D01*
X2094923Y1934334D01*
X2093613Y1933168D01*
X2092303Y1932876D01*
G01X2109803Y1950376D02*
Y1932876D01*
G01X2106746Y1944542D02*
X2112860D01*
G01X2124028Y1940751D02*
X2131015D01*
X2130360Y1942793D01*
X2129268Y1943959D01*
X2127740Y1944542D01*
X2126211Y1944251D01*
X2124901Y1943376D01*
X2124028Y1941334D01*
X2123591Y1939584D01*
Y1937834D01*
X2124028Y1936084D01*
X2125120Y1934334D01*
X2126430Y1933168D01*
X2127958Y1932876D01*
X2129486Y1933459D01*
X2131015Y1935209D01*
G01X2141528Y1934917D02*
X2142620Y1933751D01*
X2144148Y1932876D01*
X2145458D01*
X2146768Y1933459D01*
X2147641Y1934334D01*
X2148078Y1935500D01*
X2147860Y1937251D01*
X2146986Y1938126D01*
X2143056Y1939876D01*
X2142183Y1941918D01*
X2142620Y1943376D01*
X2143493Y1944251D01*
X2144803Y1944542D01*
X2146113Y1944251D01*
X2147423Y1943376D01*
G01X2179803Y1950376D02*
Y1932876D01*
G01X2176746Y1944542D02*
X2182860D01*
G01X2193591Y1932876D02*
Y1950376D01*
G01Y1941918D02*
X2194683Y1943376D01*
X2195775Y1944251D01*
X2197521Y1944542D01*
X2198831Y1944251D01*
X2200360Y1943084D01*
X2201015Y1941334D01*
Y1932876D01*
G01X2218733D02*
Y1944542D01*
G01Y1942501D02*
X2217860Y1943667D01*
X2216549Y1944251D01*
X2215021Y1944542D01*
X2213493Y1943959D01*
X2212183Y1942793D01*
X2211309Y1941043D01*
X2210873Y1938709D01*
X2211309Y1936376D01*
X2212183Y1934626D01*
X2213493Y1933459D01*
X2215021Y1932876D01*
X2216549Y1933168D01*
X2217860Y1934042D01*
X2218733Y1935209D01*
G01X2232303Y1950376D02*
Y1932876D01*
G01X2229246Y1944542D02*
X2235360D01*
G01X2267303Y1950376D02*
Y1932876D01*
G01X2264246Y1944542D02*
X2270360D01*
G01X2281091Y1932876D02*
Y1950376D01*
G01Y1941918D02*
X2282183Y1943376D01*
X2283275Y1944251D01*
X2285021Y1944542D01*
X2286331Y1944251D01*
X2287860Y1943084D01*
X2288515Y1941334D01*
Y1932876D01*
G01X2302303Y1944542D02*
Y1932876D01*
G01Y1949209D02*
X2301866Y1949501D01*
Y1950084D01*
X2302303Y1950376D01*
X2302740Y1950084D01*
Y1949501D01*
X2302303Y1949209D01*
G01X2316528Y1934917D02*
X2317620Y1933751D01*
X2319148Y1932876D01*
X2320458D01*
X2321768Y1933459D01*
X2322641Y1934334D01*
X2323078Y1935500D01*
X2322860Y1937251D01*
X2321986Y1938126D01*
X2318056Y1939876D01*
X2317183Y1941918D01*
X2317620Y1943376D01*
X2318493Y1944251D01*
X2319803Y1944542D01*
X2321113Y1944251D01*
X2322423Y1943376D01*
G01X2352183Y1950376D02*
X2357423D01*
G01X2354803D02*
Y1932876D01*
G01X2352183D02*
X2357423D01*
G01X2365753D02*
Y1944542D01*
G01Y1941334D02*
X2366408Y1942793D01*
X2367500Y1943959D01*
X2369028Y1944542D01*
X2370556Y1943959D01*
X2371648Y1942793D01*
X2372303Y1941334D01*
Y1932876D01*
G01Y1941334D02*
X2372958Y1942793D01*
X2374049Y1943959D01*
X2375578Y1944542D01*
X2377106Y1943959D01*
X2378198Y1942793D01*
X2378853Y1941043D01*
Y1932876D01*
G01X2385873Y1927043D02*
Y1944542D01*
G01Y1941918D02*
X2386965Y1943376D01*
X2388056Y1944251D01*
X2389803Y1944542D01*
X2391331Y1944251D01*
X2392860Y1942793D01*
X2393515Y1940751D01*
X2393733Y1938709D01*
X2393515Y1936667D01*
X2392860Y1934626D01*
X2391549Y1933459D01*
X2389803Y1932876D01*
X2388275Y1933168D01*
X2386746Y1934042D01*
X2385873Y1935209D01*
G01X2404028Y1940751D02*
X2411015D01*
X2410360Y1942793D01*
X2409268Y1943959D01*
X2407740Y1944542D01*
X2406211Y1944251D01*
X2404901Y1943376D01*
X2404028Y1941334D01*
X2403591Y1939584D01*
Y1937834D01*
X2404028Y1936084D01*
X2405120Y1934334D01*
X2406430Y1933168D01*
X2407958Y1932876D01*
X2409486Y1933459D01*
X2411015Y1935209D01*
G01X2428733Y1950376D02*
Y1932876D01*
G01Y1935500D02*
X2427860Y1934042D01*
X2426549Y1933168D01*
X2425021Y1932876D01*
X2423275Y1933459D01*
X2421965Y1934917D01*
X2421091Y1936667D01*
X2420873Y1938709D01*
X2421091Y1940751D01*
X2421965Y1942501D01*
X2423275Y1943959D01*
X2425021Y1944542D01*
X2426549Y1944251D01*
X2427641Y1943667D01*
X2428733Y1942501D01*
G01X2446233Y1932876D02*
Y1944542D01*
G01Y1942501D02*
X2445360Y1943667D01*
X2444049Y1944251D01*
X2442521Y1944542D01*
X2440993Y1943959D01*
X2439683Y1942793D01*
X2438809Y1941043D01*
X2438373Y1938709D01*
X2438809Y1936376D01*
X2439683Y1934626D01*
X2440993Y1933459D01*
X2442521Y1932876D01*
X2444049Y1933168D01*
X2445360Y1934042D01*
X2446233Y1935209D01*
G01X2456091Y1932876D02*
Y1944542D01*
G01Y1941626D02*
X2456965Y1943084D01*
X2458275Y1944251D01*
X2460021Y1944542D01*
X2461549Y1944251D01*
X2462860Y1943084D01*
X2463515Y1941043D01*
Y1932876D01*
G01X2480796Y1943084D02*
X2479268Y1944251D01*
X2477958Y1944542D01*
X2476211Y1943959D01*
X2474901Y1942793D01*
X2474028Y1940751D01*
X2473809Y1938709D01*
X2474028Y1936667D01*
X2474901Y1934917D01*
X2476211Y1933459D01*
X2477958Y1932876D01*
X2479486Y1933459D01*
X2480796Y1934626D01*
G01X2491528Y1940751D02*
X2498515D01*
X2497860Y1942793D01*
X2496768Y1943959D01*
X2495240Y1944542D01*
X2493711Y1944251D01*
X2492401Y1943376D01*
X2491528Y1941334D01*
X2491091Y1939584D01*
Y1937834D01*
X2491528Y1936084D01*
X2492620Y1934334D01*
X2493930Y1933168D01*
X2495458Y1932876D01*
X2496986Y1933459D01*
X2498515Y1935209D01*
G01X2039803Y1909892D02*
Y1898226D01*
G01Y1914559D02*
X2039366Y1914851D01*
Y1915434D01*
X2039803Y1915726D01*
X2040240Y1915434D01*
Y1914851D01*
X2039803Y1914559D01*
G01X2054028Y1900267D02*
X2055120Y1899101D01*
X2056648Y1898226D01*
X2057958D01*
X2059268Y1898809D01*
X2060141Y1899684D01*
X2060578Y1900850D01*
X2060360Y1902601D01*
X2059486Y1903476D01*
X2055556Y1905226D01*
X2054683Y1907268D01*
X2055120Y1908726D01*
X2055993Y1909601D01*
X2057303Y1909892D01*
X2058613Y1909601D01*
X2059923Y1908726D01*
G01X2087281Y1898226D02*
Y1915726D01*
X2097325Y1898226D01*
Y1915726D01*
G01X2109803Y1898226D02*
X2108056Y1898518D01*
X2106528Y1899684D01*
X2105218Y1901434D01*
X2104344Y1903476D01*
X2103908Y1905809D01*
Y1908143D01*
X2104344Y1910476D01*
X2105218Y1912518D01*
X2106528Y1914267D01*
X2108056Y1915434D01*
X2109803Y1915726D01*
X2111549Y1915434D01*
X2113078Y1914267D01*
X2114388Y1912518D01*
X2115262Y1910476D01*
X2115698Y1908143D01*
Y1905809D01*
X2115262Y1903476D01*
X2114388Y1901434D01*
X2113078Y1899684D01*
X2111549Y1898518D01*
X2109803Y1898226D01*
G01X2127303Y1915726D02*
Y1898226D01*
G01X2122281Y1915726D02*
X2132325D01*
G01X2158591Y1909892D02*
Y1901726D01*
X2159465Y1899684D01*
X2160775Y1898518D01*
X2162303Y1898226D01*
X2163831Y1898518D01*
X2165141Y1899684D01*
X2166015Y1901726D01*
G01Y1898226D02*
Y1909892D01*
G01X2176528Y1900267D02*
X2177620Y1899101D01*
X2179148Y1898226D01*
X2180458D01*
X2181768Y1898809D01*
X2182641Y1899684D01*
X2183078Y1900850D01*
X2182860Y1902601D01*
X2181986Y1903476D01*
X2178056Y1905226D01*
X2177183Y1907268D01*
X2177620Y1908726D01*
X2178493Y1909601D01*
X2179803Y1909892D01*
X2181113Y1909601D01*
X2182423Y1908726D01*
G01X2194028Y1906101D02*
X2201015D01*
X2200360Y1908143D01*
X2199268Y1909309D01*
X2197740Y1909892D01*
X2196211Y1909601D01*
X2194901Y1908726D01*
X2194028Y1906684D01*
X2193591Y1904934D01*
Y1903184D01*
X2194028Y1901434D01*
X2195120Y1899684D01*
X2196430Y1898518D01*
X2197958Y1898226D01*
X2199486Y1898809D01*
X2201015Y1900559D01*
G01X2218733Y1915726D02*
Y1898226D01*
G01Y1900850D02*
X2217860Y1899392D01*
X2216549Y1898518D01*
X2215021Y1898226D01*
X2213275Y1898809D01*
X2211965Y1900267D01*
X2211091Y1902017D01*
X2210873Y1904059D01*
X2211091Y1906101D01*
X2211965Y1907851D01*
X2213275Y1909309D01*
X2215021Y1909892D01*
X2216549Y1909601D01*
X2217641Y1909017D01*
X2218733Y1907851D01*
G01X-7874Y0D02*
X-75552D01*
G02X-90552Y15000I0J15000D01*
G01Y519024D01*
G02X-75552Y534024I15000J0D01*
G01X-7874D01*
G01Y1030087D02*
X-75552D01*
G03X-90552Y1015087I0J-15000D01*
G01Y1001780D01*
G03X-75552Y986780I15000J0D01*
G01X-7874D01*
G01Y1992126D02*
X-75552D01*
G03X-90552Y1977126I0J-15000D01*
G01Y1915165D01*
G03X-75552Y1900165I15000J0D01*
G01X-7874D01*
G01X1023228Y1618051D02*
Y1675945D01*
G02X1028701Y1681417I5472J0D01*
G01X1033465D01*
X1037402Y1685354D01*
Y1988189D01*
G03X1033465Y1992126I-3937J0D01*
G01X3937D01*
G03X0Y1988189I0J-3937D01*
G01Y1661189D01*
X1969Y1659220D01*
X17323D01*
G02Y1650559I0J-4331D01*
G01X1969D01*
X0Y1648591D01*
Y1243866D01*
X1969Y1241898D01*
X17323D01*
G02Y1233236I0J-4331D01*
G01X1969D01*
X0Y1231268D01*
Y747803D01*
X1969Y745835D01*
X17323D01*
G02Y737173I0J-4331D01*
G01X1969D01*
X0Y735205D01*
Y3937D01*
G03X3937Y0I3937J0D01*
G01X121260D01*
X127310Y11888D01*
G03X127953Y14567I-5263J2680D01*
G01Y17717D01*
G02X139764I5906J0D01*
G01Y14567D01*
G03X140406Y11888I5906J-1D01*
G01X146457Y0D01*
X1033465D01*
G03X1037402Y3937I0J3937D01*
G01Y1424882D01*
X1033465Y1428819D01*
X1028701D01*
G02X1023228Y1434291I0J5473D01*
G01Y1609902D01*
X1021260Y1611870D01*
X993681D01*
G02Y1616083I0J2107D01*
G01X1021260D01*
X1023228Y1618051D01*
G01X-7874Y39059D02*
G03X0I3937J0D01*
G01Y8350D02*
G03X-7874I-3937J0D01*
G01D02*
Y0D01*
G01Y251657D02*
Y39059D01*
G01X0Y251657D02*
G03X-7874I-3937J0D01*
G01Y282366D02*
G03X0I3937J0D01*
G01X-7874Y494965D02*
Y282366D01*
G01Y525673D02*
G03X0I3937J0D01*
G01Y494965D02*
G03X-7874I-3937J0D01*
G01Y534024D02*
Y525673D01*
G01X0Y993079D02*
G03X-7874I-3937J0D01*
G01Y986780D02*
Y993079D01*
G01Y1023787D02*
G03X0I3937J0D01*
G01X-7874D02*
Y1030087D01*
G01Y1930791D02*
Y1900165D01*
G01X0Y1930791D02*
G03X-7874I-3937J0D01*
G01Y1961500D02*
G03X0I3937J0D01*
G01X-7874Y1992126D02*
Y1961500D01*
G01X1045276Y0D02*
X1112953D01*
G03X1127953Y15000I0J15000D01*
G01Y493259D01*
G01X1045276Y25827D02*
G03X1037402I-3937J0D01*
G01X1045276Y0D02*
Y25827D01*
G01X1037402Y56535D02*
G03X1045276I3937J0D01*
G01D02*
Y284882D01*
G01X1037402Y315591D02*
G03X1045276I3937J0D01*
G01Y284882D02*
G03X1037402I-3937J0D01*
G01X1045276Y315591D02*
Y543937D01*
G01D02*
G03X1037402I-3937J0D01*
G01Y574646D02*
G03X1045276I3937J0D01*
G01D02*
Y802992D01*
G01X1037402Y833701D02*
G03X1045276I3937J0D01*
G01Y802992D02*
G03X1037402I-3937J0D01*
G01X1045276Y833701D02*
Y1062047D01*
G01D02*
G03X1037402I-3937J0D01*
G01Y1092756D02*
G03X1045276I3937J0D01*
G01D02*
Y1321102D01*
G01D02*
G03X1037402I-3937J0D01*
G01Y1351811D02*
G03X1045276I3937J0D01*
G01D02*
Y1377638D01*
G01D02*
X1112953D01*
G02X1127953Y1362638I0J-15000D01*
G01Y501133D01*
G01X1045276Y1732598D02*
X1112953D01*
G03X1127953Y1747598I0J15000D01*
G01Y1977126D01*
G03X1112953Y1992126I-15000J0D01*
G01X1045276D01*
G01X1037402Y1767835D02*
G03X1045276I3937J0D01*
G01Y1737126D02*
G03X1037402I-3937J0D01*
G01X1045276Y1767835D02*
Y1956890D01*
G01Y1732598D02*
Y1737126D01*
G01X1037402Y1987598D02*
G03X1045276I3937J0D01*
G01Y1956890D02*
G03X1037402I-3937J0D01*
G01X1045276Y1987598D02*
Y1992126D01*
G01X1127953Y501133D02*
G03Y493259I0J-3937D01*
G54D12*
G01X15175Y603722D02*
X26529D01*
G01X15575Y602521D02*
X26530D01*
G01X15575D02*
X26530D01*
G01X15175Y603722D02*
X26529D01*
G01X15175Y628919D02*
X26529D01*
G01X15575Y627718D02*
X26530D01*
G01X15575D02*
X26530D01*
G01X15175Y628919D02*
X26529D01*
G01X15376Y616270D02*
X26528D01*
G01X15376Y615069D02*
X26531D01*
G01X15376D02*
X26531D01*
G01X15376Y616270D02*
X26528D01*
G01X15175Y628919D02*
X26529D01*
G01X15575Y627718D02*
X26530D01*
G01X15575D02*
X26530D01*
G01X15175Y628919D02*
X26529D01*
G01X15376Y616270D02*
X26528D01*
G01X15376Y615069D02*
X26531D01*
G01X15376D02*
X26531D01*
G01X15376Y616270D02*
X26528D01*
G01X15175Y603722D02*
X26529D01*
G01X15575Y602521D02*
X26530D01*
G01X15575D02*
X26530D01*
G01X15175Y603722D02*
X26529D01*
G01X15175Y666714D02*
X26528D01*
G01X15575Y665513D02*
X26531D01*
G01X15575D02*
X26531D01*
G01X15175Y666714D02*
X26528D01*
G01X15175Y691911D02*
X26529D01*
G01X15575Y690710D02*
X26530D01*
G01X15575D02*
X26530D01*
G01X15175Y691911D02*
X26529D01*
G01X15175Y679312D02*
X26528D01*
G01X15575Y678111D02*
X26531D01*
G01X15575D02*
X26531D01*
G01X15175Y679312D02*
X26528D01*
G01X15175Y641517D02*
X26528D01*
G01X15575Y640316D02*
X26531D01*
G01X15575D02*
X26531D01*
G01X15175Y641517D02*
X26528D01*
G01X15175D02*
X26528D01*
G01X15575Y640316D02*
X26531D01*
G01X15575D02*
X26531D01*
G01X15175Y641517D02*
X26528D01*
G01X15175Y691911D02*
X26529D01*
G01X15575Y690710D02*
X26530D01*
G01X15575D02*
X26530D01*
G01X15175Y691911D02*
X26529D01*
G01X15175Y679312D02*
X26528D01*
G01X15575Y678111D02*
X26531D01*
G01X15575D02*
X26531D01*
G01X15175Y679312D02*
X26528D01*
G01X15175Y666714D02*
X26528D01*
G01X15575Y665513D02*
X26531D01*
G01X15575D02*
X26531D01*
G01X15175Y666714D02*
X26528D01*
G01X15376Y773600D02*
X26528D01*
G01X15376Y772399D02*
X26531D01*
G01X15376D02*
X26531D01*
G01X15376Y773600D02*
X26528D01*
G01X15376Y761002D02*
X26528D01*
G01X15376Y759801D02*
X26531D01*
G01X15376D02*
X26531D01*
G01X15376Y761002D02*
X26528D01*
G01X15376Y729506D02*
X26528D01*
G01X15376Y728305D02*
X26531D01*
G01X15376D02*
X26531D01*
G01X15376Y729506D02*
X26528D01*
G01X15376Y716907D02*
X26528D01*
G01X15376Y715706D02*
X26531D01*
G01X15376D02*
X26531D01*
G01X15376Y716907D02*
X26528D01*
G01X15175Y704509D02*
X26528D01*
G01X15575Y703308D02*
X26531D01*
G01X15575D02*
X26531D01*
G01X15175Y704509D02*
X26528D01*
G01X15376Y773600D02*
X26528D01*
G01X15376Y772399D02*
X26531D01*
G01X15376D02*
X26531D01*
G01X15376Y773600D02*
X26528D01*
G01X15175Y704509D02*
X26528D01*
G01X15575Y703308D02*
X26531D01*
G01X15376Y761002D02*
X26528D01*
G01X15376Y759801D02*
X26531D01*
G01X15376D02*
X26531D01*
G01X15376Y761002D02*
X26528D01*
G01X15376Y729506D02*
X26528D01*
G01X15376Y728305D02*
X26531D01*
G01X15376D02*
X26531D01*
G01X15376Y729506D02*
X26528D01*
G01X15376Y716907D02*
X26528D01*
G01X15376Y715706D02*
X26531D01*
G01X15376D02*
X26531D01*
G01X15376Y716907D02*
X26528D01*
G01X15575Y703308D02*
X26531D01*
G01X15175Y704509D02*
X26528D01*
G01X15376Y833443D02*
X26528D01*
G01X15376Y832242D02*
X26531D01*
G01X15376D02*
X26531D01*
G01X15376Y833443D02*
X26528D01*
G01X15376Y820844D02*
X26528D01*
G01X15376Y819643D02*
X26531D01*
G01X15376D02*
X26531D01*
G01X15376Y820844D02*
X26528D01*
G01X15376Y808246D02*
X26528D01*
G01X15376Y807045D02*
X26531D01*
G01X15376D02*
X26531D01*
G01X15376Y808246D02*
X26528D01*
G01X15376Y795647D02*
X26528D01*
G01X15376Y794446D02*
X26531D01*
G01X15376D02*
X26531D01*
G01X15376Y795647D02*
X26528D01*
G01X15376Y845841D02*
X26528D01*
G01X15376Y844640D02*
X26531D01*
G01X15376D02*
X26531D01*
G01X15376Y845841D02*
X26528D01*
G01X15376Y833443D02*
X26528D01*
G01X15376Y832242D02*
X26531D01*
G01X15376D02*
X26531D01*
G01X15376Y833443D02*
X26528D01*
G01X15376Y820844D02*
X26528D01*
G01X15376Y819643D02*
X26531D01*
G01X15376D02*
X26531D01*
G01X15376Y820844D02*
X26528D01*
G01X15376Y808246D02*
X26528D01*
G01X15376Y807045D02*
X26531D01*
G01X15376D02*
X26531D01*
G01X15376Y808246D02*
X26528D01*
G01X15376Y795647D02*
X26528D01*
G01X15376Y794446D02*
X26531D01*
G01X15376D02*
X26531D01*
G01X15376Y795647D02*
X26528D01*
G01X15376Y845841D02*
X26528D01*
G01X15376Y844640D02*
X26531D01*
G01X15376D02*
X26531D01*
G01X15376Y845841D02*
X26528D01*
G01X15376Y909033D02*
X26528D01*
G01X15376Y907832D02*
X26531D01*
G01X15376D02*
X26531D01*
G01X15376Y909033D02*
X26528D01*
G01X15376Y896435D02*
X26528D01*
G01X15376Y895234D02*
X26531D01*
G01X15376D02*
X26531D01*
G01X15376Y896435D02*
X26528D01*
G01X15376Y883686D02*
X26528D01*
G01X15376Y882485D02*
X26531D01*
G01X15376D02*
X26531D01*
G01X15376Y883686D02*
X26528D01*
G01X15376Y871038D02*
X26528D01*
G01X15376Y869837D02*
X26531D01*
G01X15376D02*
X26531D01*
G01X15376Y871038D02*
X26528D01*
G01X15376Y858440D02*
X26528D01*
G01X15376Y857239D02*
X26531D01*
G01X15376D02*
X26531D01*
G01X15376Y858440D02*
X26528D01*
G01X15376Y883686D02*
X26528D01*
G01X15376Y882485D02*
X26531D01*
G01X15376D02*
X26531D01*
G01X15376Y883686D02*
X26528D01*
G01X15376Y871038D02*
X26528D01*
G01X15376Y869837D02*
X26531D01*
G01X15376D02*
X26531D01*
G01X15376Y871038D02*
X26528D01*
G01X15376Y909033D02*
X26528D01*
G01X15376Y907832D02*
X26531D01*
G01X15376D02*
X26531D01*
G01X15376Y909033D02*
X26528D01*
G01X15376Y858440D02*
X26528D01*
G01X15376Y857239D02*
X26531D01*
G01X15376D02*
X26531D01*
G01X15376Y858440D02*
X26528D01*
G01X15376Y896435D02*
X26528D01*
G01X15376Y895234D02*
X26531D01*
G01X15376D02*
X26531D01*
G01X15376Y896435D02*
X26528D01*
G01X13000Y1018699D02*
X42639Y989060D01*
G01X11799Y1018201D02*
X41438Y988562D01*
G01X11799Y1018201D02*
X41438Y988562D01*
G01X13000Y1018699D02*
X42639Y989060D01*
G01X13000Y1018699D02*
X42639Y989060D01*
G01X11799Y1018201D02*
X41438Y988562D01*
G01X13000Y1018699D02*
X42639Y989060D01*
G01X11799Y1018201D02*
X41438Y988562D01*
G01X11799Y1018201D02*
X41438Y988562D01*
G01X13000Y1018699D02*
X42639Y989060D01*
G01X11799Y1018201D02*
X41438Y988562D01*
G01X13000Y1018699D02*
X42639Y989060D01*
G01X13000Y1018699D02*
X42639Y989060D01*
G01X11799Y1018201D02*
X41438Y988562D01*
G01X11799Y1018201D02*
X41438Y988562D01*
G01X13000Y1018699D02*
X42639Y989060D01*
G01X13000Y1038500D02*
Y1018699D01*
G01X11799Y1038998D02*
Y1018201D01*
G01X25500Y1051000D02*
X13000Y1038500D01*
G01X25002Y1052201D02*
X11799Y1038998D01*
G01X47500Y1051000D02*
X25500D01*
G01X47002Y1052201D02*
X25002D01*
G01X11799Y1038998D02*
Y1018201D01*
G01X13000Y1038500D02*
Y1018699D01*
G01X25002Y1052201D02*
X11799Y1038998D01*
G01X25500Y1051000D02*
X13000Y1038500D01*
G01X47002Y1052201D02*
X25002D01*
G01X47500Y1051000D02*
X25500D01*
G01X13000Y1038500D02*
Y1018699D01*
G01X11799Y1038998D02*
Y1018201D01*
G01X25500Y1051000D02*
X13000Y1038500D01*
G01X25002Y1052201D02*
X11799Y1038998D01*
G01X47500Y1051000D02*
X25500D01*
G01X47002Y1052201D02*
X25002D01*
G01X13000Y1038500D02*
Y1018699D01*
G01X11799Y1038998D02*
Y1018201D01*
G01X25500Y1051000D02*
X13000Y1038500D01*
G01X25002Y1052201D02*
X11799Y1038998D01*
G01X47500Y1051000D02*
X25500D01*
G01X47002Y1052201D02*
X25002D01*
G01X11799Y1038998D02*
Y1018201D01*
G01X13000Y1038500D02*
Y1018699D01*
G01X25002Y1052201D02*
X11799Y1038998D01*
G01X25500Y1051000D02*
X13000Y1038500D01*
G01X47002Y1052201D02*
X25002D01*
G01X47500Y1051000D02*
X25500D01*
G01X11799Y1038998D02*
Y1018201D01*
G01X13000Y1038500D02*
Y1018699D01*
G01X25002Y1052201D02*
X11799Y1038998D01*
G01X25500Y1051000D02*
X13000Y1038500D01*
G01X47002Y1052201D02*
X25002D01*
G01X47500Y1051000D02*
X25500D01*
G01X13000Y1038500D02*
Y1018699D01*
G01X11799Y1038998D02*
Y1018201D01*
G01X25500Y1051000D02*
X13000Y1038500D01*
G01X25002Y1052201D02*
X11799Y1038998D01*
G01X47500Y1051000D02*
X25500D01*
G01X47002Y1052201D02*
X25002D01*
G01X11799Y1038998D02*
Y1018201D01*
G01X13000Y1038500D02*
Y1018699D01*
G01X25002Y1052201D02*
X11799Y1038998D01*
G01X25500Y1051000D02*
X13000Y1038500D01*
G01X47002Y1052201D02*
X25002D01*
G01X47500Y1051000D02*
X25500D01*
G01X15376Y1137380D02*
X26528D01*
G01X15376Y1136179D02*
X26531D01*
G01X15376D02*
X26531D01*
G01X15376Y1137380D02*
X26528D01*
G01X26445Y1112300D02*
X15258D01*
G01X26614Y1111099D02*
X15492D01*
G01X26614D02*
X15492D01*
G01X26445Y1112300D02*
X15258D01*
G01X15225Y1099735D02*
X26479D01*
G01X15234Y1098534D02*
X26580D01*
G01X15234D02*
X26580D01*
G01X15225Y1099735D02*
X26479D01*
G01X26445Y1112300D02*
X15258D01*
G01X26614Y1111099D02*
X15492D01*
G01X26614D02*
X15492D01*
G01X26445Y1112300D02*
X15258D01*
G01X15225Y1099735D02*
X26479D01*
G01X15234Y1098534D02*
X26580D01*
G01X15234D02*
X26580D01*
G01X15225Y1099735D02*
X26479D01*
G01X15376Y1137380D02*
X26528D01*
G01X15376Y1136179D02*
X26531D01*
G01X15376D02*
X26531D01*
G01X15376Y1137380D02*
X26528D01*
G01X15376Y1175175D02*
X26528D01*
G01X15376Y1173974D02*
X26531D01*
G01X15376D02*
X26531D01*
G01X15376Y1175175D02*
X26528D01*
G01X15376Y1162577D02*
X26528D01*
G01X15376Y1161376D02*
X26531D01*
G01X15376D02*
X26531D01*
G01X15376Y1162577D02*
X26528D01*
G01X15376Y1149978D02*
X26528D01*
G01X15376Y1148777D02*
X26531D01*
G01X15376D02*
X26531D01*
G01X15376Y1149978D02*
X26528D01*
G01X15376Y1200372D02*
X26528D01*
G01X15376Y1199171D02*
X26531D01*
G01X15376D02*
X26531D01*
G01X15376Y1200372D02*
X26528D01*
G01X15376Y1187773D02*
X26528D01*
G01X15376Y1186572D02*
X26531D01*
G01X15376D02*
X26531D01*
G01X15376Y1187773D02*
X26528D01*
G01X15376Y1175175D02*
X26528D01*
G01X15376Y1173974D02*
X26531D01*
G01X15376D02*
X26531D01*
G01X15376Y1175175D02*
X26528D01*
G01X15376Y1162577D02*
X26528D01*
G01X15376Y1161376D02*
X26531D01*
G01X15376D02*
X26531D01*
G01X15376Y1162577D02*
X26528D01*
G01X15376Y1200372D02*
X26528D01*
G01X15376Y1199171D02*
X26531D01*
G01X15376D02*
X26531D01*
G01X15376Y1200372D02*
X26528D01*
G01X15376Y1149978D02*
X26528D01*
G01X15376Y1148777D02*
X26531D01*
G01X15376D02*
X26531D01*
G01X15376Y1149978D02*
X26528D01*
G01X15376Y1187773D02*
X26528D01*
G01X15376Y1186572D02*
X26531D01*
G01X15376D02*
X26531D01*
G01X15376Y1187773D02*
X26528D01*
G01X15376Y1282262D02*
X26528D01*
G01X15376Y1281061D02*
X26531D01*
G01X15376D02*
X26531D01*
G01X15376Y1282262D02*
X26528D01*
G01X15376Y1269663D02*
X26528D01*
G01X15376Y1268462D02*
X26531D01*
G01X15376D02*
X26531D01*
G01X15376Y1269663D02*
X26528D01*
G01X15376Y1257065D02*
X26528D01*
G01X15376Y1255864D02*
X26531D01*
G01X15376D02*
X26531D01*
G01X15376Y1257065D02*
X26528D01*
G01X15376Y1225569D02*
X26528D01*
G01X15376Y1224368D02*
X26531D01*
G01X15376D02*
X26531D01*
G01X15376Y1225569D02*
X26528D01*
G01X15376Y1212970D02*
X26528D01*
G01X15376Y1211769D02*
X26531D01*
G01X15376D02*
X26531D01*
G01X15376Y1212970D02*
X26528D01*
G01X15376Y1225569D02*
X26528D01*
G01X15376Y1224368D02*
X26531D01*
G01X15376D02*
X26531D01*
G01X15376Y1225569D02*
X26528D01*
G01X15376Y1212970D02*
X26528D01*
G01X15376Y1211769D02*
X26531D01*
G01X15376Y1282262D02*
X26528D01*
G01X15376Y1281061D02*
X26531D01*
G01X15376D02*
X26531D01*
G01X15376Y1282262D02*
X26528D01*
G01X15376Y1269663D02*
X26528D01*
G01X15376Y1268462D02*
X26531D01*
G01X15376D02*
X26531D01*
G01X15376Y1269663D02*
X26528D01*
G01X15376Y1257065D02*
X26528D01*
G01X15376Y1255864D02*
X26531D01*
G01X15376D02*
X26531D01*
G01X15376Y1257065D02*
X26528D01*
G01X15376Y1211769D02*
X26531D01*
G01X15376Y1212970D02*
X26528D01*
G01X15376Y1294860D02*
X26528D01*
G01X15376Y1293659D02*
X26531D01*
G01X15376D02*
X26531D01*
G01X15376Y1294860D02*
X26528D01*
G01X15175Y1317108D02*
X26529D01*
G01X15575Y1315907D02*
X26530D01*
G01X15575D02*
X26530D01*
G01X15175Y1317108D02*
X26529D01*
G01X15175Y1342305D02*
X26529D01*
G01X15575Y1341104D02*
X26530D01*
G01X15575D02*
X26530D01*
G01X15175Y1342305D02*
X26529D01*
G01X15175Y1329706D02*
X26528D01*
G01X15575Y1328505D02*
X26531D01*
G01X15575D02*
X26531D01*
G01X15175Y1329706D02*
X26528D01*
G01X15175Y1354903D02*
X26528D01*
G01X15575Y1353702D02*
X26531D01*
G01X15575D02*
X26531D01*
G01X15175Y1354903D02*
X26528D01*
G01X15376Y1294860D02*
X26528D01*
G01X15376Y1293659D02*
X26531D01*
G01X15376D02*
X26531D01*
G01X15376Y1294860D02*
X26528D01*
G01X15175Y1354903D02*
X26528D01*
G01X15575Y1353702D02*
X26531D01*
G01X15575D02*
X26531D01*
G01X15175Y1354903D02*
X26528D01*
G01X15175Y1342305D02*
X26529D01*
G01X15575Y1341104D02*
X26530D01*
G01X15575D02*
X26530D01*
G01X15175Y1342305D02*
X26529D01*
G01X15175Y1329706D02*
X26528D01*
G01X15575Y1328505D02*
X26531D01*
G01X15575D02*
X26531D01*
G01X15175Y1329706D02*
X26528D01*
G01X15175Y1317108D02*
X26529D01*
G01X15575Y1315907D02*
X26530D01*
G01X15575D02*
X26530D01*
G01X15175Y1317108D02*
X26529D01*
G01X15375Y1405097D02*
X26529D01*
G01X15375Y1403896D02*
X26530D01*
G01X15375D02*
X26530D01*
G01X15375Y1405097D02*
X26529D01*
G01X15376Y1392498D02*
X26528D01*
G01X15376Y1391297D02*
X26531D01*
G01X15376D02*
X26531D01*
G01X15376Y1392498D02*
X26528D01*
G01X15376Y1379899D02*
X26528D01*
G01X15376Y1378698D02*
X26531D01*
G01X15376D02*
X26531D01*
G01X15376Y1379899D02*
X26528D01*
G01X15376Y1367301D02*
X26528D01*
G01X15376Y1366100D02*
X26531D01*
G01X15376D02*
X26531D01*
G01X15376Y1367301D02*
X26528D01*
G01X15375Y1405097D02*
X26529D01*
G01X15375Y1403896D02*
X26530D01*
G01X15375D02*
X26530D01*
G01X15375Y1405097D02*
X26529D01*
G01X15376Y1392498D02*
X26528D01*
G01X15376Y1391297D02*
X26531D01*
G01X15376D02*
X26531D01*
G01X15376Y1392498D02*
X26528D01*
G01X15376Y1379899D02*
X26528D01*
G01X15376Y1378698D02*
X26531D01*
G01X15376D02*
X26531D01*
G01X15376Y1379899D02*
X26528D01*
G01X15376Y1367301D02*
X26528D01*
G01X15376Y1366100D02*
X26531D01*
G01X15376D02*
X26531D01*
G01X15376Y1367301D02*
X26528D01*
G01X36400Y1499499D02*
Y1503500D01*
G01X35199Y1483801D02*
Y1503002D01*
G01X36400Y1494365D02*
Y1496429D01*
G01X35199Y1483801D02*
Y1503002D01*
G01X36400Y1484299D02*
Y1491295D01*
G01X35199Y1483801D02*
Y1503002D01*
G01X50000Y1470699D02*
X36400Y1484299D01*
G01X48799Y1470201D02*
X35199Y1483801D01*
G01D02*
Y1503002D01*
G01X36400Y1499499D02*
Y1503500D01*
G01Y1494365D02*
Y1496429D01*
G01Y1484299D02*
Y1491295D01*
G01X48799Y1470201D02*
X35199Y1483801D01*
G01X50000Y1470699D02*
X36400Y1484299D01*
G01X29035Y1480965D02*
X44511Y1465489D01*
G01X27834Y1480467D02*
X43310Y1464991D01*
G01X29035Y1487185D02*
Y1480965D01*
G01X27834Y1487116D02*
Y1480467D01*
G01D02*
X43310Y1464991D01*
G01X29035Y1480965D02*
X44511Y1465489D01*
G01X27834Y1487116D02*
Y1480467D01*
G01X29035Y1487185D02*
Y1480965D01*
G01X36400Y1499499D02*
Y1503500D01*
G01X35199Y1483801D02*
Y1503002D01*
G01X36400Y1494365D02*
Y1496429D01*
G01X35199Y1483801D02*
Y1503002D01*
G01X36400Y1484299D02*
Y1491295D01*
G01X35199Y1483801D02*
Y1503002D01*
G01X50000Y1470699D02*
X36400Y1484299D01*
G01X48799Y1470201D02*
X35199Y1483801D01*
G01X36400Y1499499D02*
Y1503500D01*
G01X35199Y1483801D02*
Y1503002D01*
G01X36400Y1494365D02*
Y1496429D01*
G01X35199Y1483801D02*
Y1503002D01*
G01X36400Y1484299D02*
Y1491295D01*
G01X35199Y1483801D02*
Y1503002D01*
G01X50000Y1470699D02*
X36400Y1484299D01*
G01X48799Y1470201D02*
X35199Y1483801D01*
G01D02*
Y1503002D01*
G01X36400Y1499499D02*
Y1503500D01*
G01Y1494365D02*
Y1496429D01*
G01Y1484299D02*
Y1491295D01*
G01X48799Y1470201D02*
X35199Y1483801D01*
G01X50000Y1470699D02*
X36400Y1484299D01*
G01X35199Y1483801D02*
Y1503002D01*
G01X36400Y1499499D02*
Y1503500D01*
G01Y1494365D02*
Y1496429D01*
G01Y1484299D02*
Y1491295D01*
G01X48799Y1470201D02*
X35199Y1483801D01*
G01X50000Y1470699D02*
X36400Y1484299D01*
G01X29035Y1480965D02*
X44511Y1465489D01*
G01X27834Y1480467D02*
X43310Y1464991D01*
G01X29035Y1487185D02*
Y1480965D01*
G01X27834Y1487116D02*
Y1480467D01*
G01X29035Y1480965D02*
X44511Y1465489D01*
G01X27834Y1480467D02*
X43310Y1464991D01*
G01X29035Y1487185D02*
Y1480965D01*
G01X27834Y1487116D02*
Y1480467D01*
G01D02*
X43310Y1464991D01*
G01X29035Y1480965D02*
X44511Y1465489D01*
G01X27834Y1487116D02*
Y1480467D01*
G01X29035Y1487185D02*
Y1480965D01*
G01X27834Y1480467D02*
X43310Y1464991D01*
G01X29035Y1480965D02*
X44511Y1465489D01*
G01X27834Y1487116D02*
Y1480467D01*
G01X29035Y1487185D02*
Y1480965D01*
G01X29000Y1493050D02*
Y1513799D01*
G01X27799Y1500969D02*
Y1503033D01*
G01Y1493049D02*
Y1497899D01*
G01X29000Y1493050D02*
Y1513799D01*
G01Y1493050D02*
Y1513799D01*
G01X27799Y1500969D02*
Y1503033D01*
G01X29000Y1493050D02*
Y1513799D01*
G01X27799Y1493049D02*
Y1497899D01*
G01X29000Y1493050D02*
Y1513799D01*
G01X36400Y1499499D02*
Y1503500D01*
G01X35199Y1483801D02*
Y1503002D01*
G01X36400Y1494365D02*
Y1496429D01*
G01X35199Y1483801D02*
Y1503002D01*
G01X36400Y1484299D02*
Y1491295D01*
G01X35199Y1483801D02*
Y1503002D01*
G01X50000Y1470699D02*
X36400Y1484299D01*
G01X48799Y1470201D02*
X35199Y1483801D01*
G01D02*
Y1503002D01*
G01X36400Y1499499D02*
Y1503500D01*
G01Y1494365D02*
Y1496429D01*
G01Y1484299D02*
Y1491295D01*
G01X48799Y1470201D02*
X35199Y1483801D01*
G01X50000Y1470699D02*
X36400Y1484299D01*
G01X29035Y1480965D02*
X44511Y1465489D01*
G01X27834Y1480467D02*
X43310Y1464991D01*
G01X29035Y1487185D02*
Y1480965D01*
G01X27834Y1487116D02*
Y1480467D01*
G01D02*
X43310Y1464991D01*
G01X29035Y1480965D02*
X44511Y1465489D01*
G01X27834Y1487116D02*
Y1480467D01*
G01X29035Y1487185D02*
Y1480965D01*
G01X15376Y1564151D02*
X26528D01*
G01X15376Y1562950D02*
X26531D01*
G01X15376D02*
X26531D01*
G01X15376Y1564151D02*
X26528D01*
G01X15375Y1551553D02*
X26529D01*
G01X15375Y1550352D02*
X26530D01*
G01X15375D02*
X26530D01*
G01X15375Y1551553D02*
X26529D01*
G01X15376Y1538954D02*
X26528D01*
G01X15376Y1537753D02*
X26531D01*
G01X15376D02*
X26531D01*
G01X15376Y1538954D02*
X26528D01*
G01X15375Y1526356D02*
X26529D01*
G01X15375Y1525155D02*
X26530D01*
G01X15375D02*
X26530D01*
G01X15375Y1526356D02*
X26529D01*
G01X35200Y1504700D02*
Y1509300D01*
G01X33999Y1504202D02*
Y1509301D01*
G01X36400Y1503500D02*
X35200Y1504700D01*
G01X35199Y1503002D02*
X33999Y1504202D01*
G01D02*
Y1509301D01*
G01X35200Y1504700D02*
Y1509300D01*
G01X35199Y1503002D02*
X33999Y1504202D01*
G01X36400Y1503500D02*
X35200Y1504700D01*
G01D02*
Y1509300D01*
G01X33999Y1504202D02*
Y1509301D01*
G01X36400Y1503500D02*
X35200Y1504700D01*
G01X35199Y1503002D02*
X33999Y1504202D01*
G01X35200Y1504700D02*
Y1509300D01*
G01X33999Y1504202D02*
Y1509301D01*
G01X36400Y1503500D02*
X35200Y1504700D01*
G01X35199Y1503002D02*
X33999Y1504202D01*
G01D02*
Y1509301D01*
G01X35200Y1504700D02*
Y1509300D01*
G01X35199Y1503002D02*
X33999Y1504202D01*
G01X36400Y1503500D02*
X35200Y1504700D01*
G01X33999Y1504202D02*
Y1509301D01*
G01X35200Y1504700D02*
Y1509300D01*
G01X35199Y1503002D02*
X33999Y1504202D01*
G01X36400Y1503500D02*
X35200Y1504700D01*
G01Y1517122D02*
Y1515100D01*
G01X33999Y1515099D02*
Y1517125D01*
G01Y1515099D02*
Y1517125D01*
G01X35200Y1517122D02*
Y1515100D01*
G01X15376Y1564151D02*
X26528D01*
G01X15376Y1562950D02*
X26531D01*
G01X15376D02*
X26531D01*
G01X15376Y1564151D02*
X26528D01*
G01X15375Y1551553D02*
X26529D01*
G01X15375Y1550352D02*
X26530D01*
G01X15375D02*
X26530D01*
G01X15375Y1551553D02*
X26529D01*
G01X15376Y1538954D02*
X26528D01*
G01X15376Y1537753D02*
X26531D01*
G01X15376D02*
X26531D01*
G01X15376Y1538954D02*
X26528D01*
G01X15375Y1526356D02*
X26529D01*
G01X15375Y1525155D02*
X26530D01*
G01X15375D02*
X26530D01*
G01X15375Y1526356D02*
X26529D01*
G01X25699Y1517100D02*
X15182D01*
G01X17632Y1515899D02*
X15568D01*
G01X25201D02*
X20702D01*
G01X29000Y1513799D02*
X25699Y1517100D01*
G01X27799Y1513301D02*
X25201Y1515899D01*
G01X27799Y1511237D02*
Y1513301D01*
G01Y1506103D02*
Y1508167D01*
G01X17632Y1515899D02*
X15568D01*
G01X25699Y1517100D02*
X15182D01*
G01X25201Y1515899D02*
X20702D01*
G01X25699Y1517100D02*
X15182D01*
G01X27799Y1513301D02*
X25201Y1515899D01*
G01X29000Y1513799D02*
X25699Y1517100D01*
G01X27799Y1511237D02*
Y1513301D01*
G01Y1506103D02*
Y1508167D01*
G01X35200Y1504700D02*
Y1509300D01*
G01X33999Y1504202D02*
Y1509301D01*
G01X36400Y1503500D02*
X35200Y1504700D01*
G01X35199Y1503002D02*
X33999Y1504202D01*
G01D02*
Y1509301D01*
G01X35200Y1504700D02*
Y1509300D01*
G01X35199Y1503002D02*
X33999Y1504202D01*
G01X36400Y1503500D02*
X35200Y1504700D01*
G01X15376Y1636592D02*
X26528D01*
G01X15376Y1635391D02*
X26531D01*
G01X15376D02*
X26531D01*
G01X15376Y1636592D02*
X26528D01*
G01X15375Y1597596D02*
X26530D01*
G01X15375Y1598797D02*
X26529D01*
G01X15375D02*
X26529D01*
G01X15375Y1597596D02*
X26530D01*
G01X15376Y1584997D02*
X26531D01*
G01X15376Y1586198D02*
X26528D01*
G01X15376D02*
X26528D01*
G01X15376Y1584997D02*
X26531D01*
G01X15376Y1622792D02*
X26531D01*
G01X15376Y1623993D02*
X26528D01*
G01X15376D02*
X26528D01*
G01X15376Y1622792D02*
X26531D01*
G01X15376Y1610194D02*
X26531D01*
G01X15376Y1611395D02*
X26528D01*
G01X15376D02*
X26528D01*
G01X15376Y1610194D02*
X26531D01*
G01X15376Y1622792D02*
X26531D01*
G01X15376Y1623993D02*
X26528D01*
G01X15376D02*
X26528D01*
G01X15376Y1622792D02*
X26531D01*
G01X15376Y1610194D02*
X26531D01*
G01X15376Y1611395D02*
X26528D01*
G01X15376D02*
X26528D01*
G01X15376Y1610194D02*
X26531D01*
G01X15375Y1597596D02*
X26530D01*
G01X15375Y1598797D02*
X26529D01*
G01X15375D02*
X26529D01*
G01X15375Y1597596D02*
X26530D01*
G01X15376Y1584997D02*
X26531D01*
G01X15376Y1586198D02*
X26528D01*
G01X15376D02*
X26528D01*
G01X15376Y1584997D02*
X26531D01*
G01X15376Y1636592D02*
X26528D01*
G01X15376Y1635391D02*
X26531D01*
G01X15376D02*
X26531D01*
G01X15376Y1636592D02*
X26528D01*
G01X26453Y1699700D02*
X15261D01*
G01X26606Y1698499D02*
X15491D01*
G01X26606D02*
X15491D01*
G01X26453Y1699700D02*
X15261D01*
G01X26452Y1687100D02*
X15261D01*
G01X26607Y1685899D02*
X15489D01*
G01X26607D02*
X15489D01*
G01X26452Y1687100D02*
X15261D01*
G01X26450Y1674500D02*
X15264D01*
G01X26609Y1673299D02*
X15488D01*
G01X26609D02*
X15488D01*
G01X26450Y1674500D02*
X15264D01*
G01X15222Y1720622D02*
X26530D01*
G01X15222D02*
X26530D01*
G01X15222D02*
X26530D01*
G01X26453Y1699700D02*
X15261D01*
G01X26606Y1698499D02*
X15491D01*
G01X26606D02*
X15491D01*
G01X26453Y1699700D02*
X15261D01*
G01X26452Y1687100D02*
X15261D01*
G01X26607Y1685899D02*
X15489D01*
G01X26607D02*
X15489D01*
G01X26452Y1687100D02*
X15261D01*
G01X26450Y1674500D02*
X15264D01*
G01X26609Y1673299D02*
X15488D01*
G01X26609D02*
X15488D01*
G01X26450Y1674500D02*
X15264D01*
G01X15222Y1720622D02*
X26530D01*
G01X34099Y1776499D02*
X44398D01*
G01X34100Y1777700D02*
X43900D01*
G01X34099Y1776499D02*
X44398D01*
G01X34100Y1777700D02*
X43900D01*
G01X34099Y1776499D02*
X44398D01*
G01X34100Y1777700D02*
X43900D01*
G01X34099Y1776499D02*
X44398D01*
G01X34100Y1777700D02*
X43900D01*
G01X34100D02*
X43900D01*
G01X34099Y1776499D02*
X44398D01*
G01X34100Y1777700D02*
X43900D01*
G01X34099Y1776499D02*
X44398D01*
G01X34100Y1777700D02*
X43900D01*
G01X34099Y1776499D02*
X44398D01*
G01X34100Y1777700D02*
X43900D01*
G01X34099Y1776499D02*
X44398D01*
G01X15566Y1758417D02*
X26530D01*
G01X15184Y1759618D02*
X26529D01*
G01X15184D02*
X26529D01*
G01X15566Y1758417D02*
X26530D01*
G01X15567Y1745819D02*
X26530D01*
G01X15185Y1747020D02*
X26529D01*
G01X15185D02*
X26529D01*
G01X15567Y1745819D02*
X26530D01*
G01X15566Y1733220D02*
X26530D01*
G01X15184Y1734421D02*
X26529D01*
G01X15184D02*
X26529D01*
G01X15566Y1733220D02*
X26530D01*
G01X15185Y1721823D02*
X26529D01*
G01X15185D02*
X26529D01*
G01X16686Y1767686D02*
X15387D01*
G01X16188Y1768887D02*
X15365D01*
G01X25500Y1776500D02*
X16686Y1767686D01*
G01X16188Y1768887D02*
X15365D01*
G01X25002Y1777701D02*
X16188Y1768887D01*
G01X28300Y1776500D02*
X25500D01*
G01X28301Y1777701D02*
X25002D01*
G01X16188Y1768887D02*
X15365D01*
G01X16686Y1767686D02*
X15387D01*
G01X25500Y1776500D02*
X16686Y1767686D01*
G01X25002Y1777701D02*
X16188Y1768887D01*
G01X25500Y1776500D02*
X16686Y1767686D01*
G01X28301Y1777701D02*
X25002D01*
G01X28300Y1776500D02*
X25500D01*
G01X27700Y1767300D02*
Y1768558D01*
G01X26499Y1766802D02*
Y1768559D01*
G01X47500Y1747500D02*
X27700Y1767300D01*
G01X32979Y1760322D02*
X26499Y1766802D01*
G01X36624Y1756677D02*
X35164Y1758137D01*
G01X40268Y1753033D02*
X38809Y1754492D01*
G01X26499Y1766802D02*
Y1768559D01*
G01X27700Y1767300D02*
Y1768558D01*
G01X32979Y1760322D02*
X26499Y1766802D01*
G01X47500Y1747500D02*
X27700Y1767300D01*
G01X36624Y1756677D02*
X35164Y1758137D01*
G01X47500Y1747500D02*
X27700Y1767300D01*
G01X40268Y1753033D02*
X38809Y1754492D01*
G01X47500Y1747500D02*
X27700Y1767300D01*
G01X47500Y1747500D02*
X27700Y1767300D01*
G01X15566Y1758417D02*
X26530D01*
G01X15184Y1759618D02*
X26529D01*
G01X15184D02*
X26529D01*
G01X15566Y1758417D02*
X26530D01*
G01X15567Y1745819D02*
X26530D01*
G01X15185Y1747020D02*
X26529D01*
G01X15185D02*
X26529D01*
G01X15567Y1745819D02*
X26530D01*
G01X15566Y1733220D02*
X26530D01*
G01X15184Y1734421D02*
X26529D01*
G01X15184D02*
X26529D01*
G01X15566Y1733220D02*
X26530D01*
G01X15185Y1721823D02*
X26529D01*
G01X34099Y1776499D02*
X44398D01*
G01X34100Y1777700D02*
X43900D01*
G01X34100D02*
X43900D01*
G01X34099Y1776499D02*
X44398D01*
G01X15185Y1721823D02*
X26529D01*
G01X94974Y64792D02*
X104001D01*
G01X95000Y65993D02*
X104000D01*
G01X95000D02*
X104000D01*
G01X94974Y64792D02*
X104001D01*
G01X94974Y83690D02*
X104001D01*
G01X95000Y84891D02*
X104000D01*
G01X95000D02*
X104000D01*
G01X94974Y83690D02*
X104001D01*
G01X94974Y102588D02*
X104000D01*
G01X95000Y103789D02*
X104001D01*
G01X95000D02*
X104001D01*
G01X94974Y102588D02*
X104000D01*
G01X97901Y55443D02*
X95543D01*
G01X97900Y56644D02*
X95308D01*
G01X97900D02*
X95308D01*
G01X97901Y55443D02*
X95543D01*
G01X94974Y74241D02*
X97901D01*
G01X94975Y75442D02*
X97900D01*
G01X94975D02*
X97900D01*
G01X94974Y74241D02*
X97901D01*
G01X95590Y93139D02*
X97901D01*
G01X95590Y94340D02*
X97900D01*
G01X95590D02*
X97900D01*
G01X95590Y93139D02*
X97901D01*
G01X110297Y119402D02*
Y142096D01*
G01X109096Y118904D02*
Y142594D01*
G01X118798Y110901D02*
X110297Y119402D01*
G01X118300Y109700D02*
X109096Y118904D01*
G01D02*
Y142594D01*
G01X110297Y119402D02*
Y142096D01*
G01X118300Y109700D02*
X109096Y118904D01*
G01X118798Y110901D02*
X110297Y119402D01*
G01X94974Y64792D02*
X104001D01*
G01X95000Y65993D02*
X104000D01*
G01X95000D02*
X104000D01*
G01X94974Y64792D02*
X104001D01*
G01X94974Y83690D02*
X104001D01*
G01X95000Y84891D02*
X104000D01*
G01X95000D02*
X104000D01*
G01X94974Y83690D02*
X104001D01*
G01X94974Y102588D02*
X104000D01*
G01X95000Y103789D02*
X104001D01*
G01X95000D02*
X104001D01*
G01X94974Y102588D02*
X104000D01*
G01X72000Y130559D02*
X69000D01*
G01X72000Y129358D02*
X68999D01*
G01X72000D02*
X68999D01*
G01X72000Y130559D02*
X69000D01*
G01X94974Y152981D02*
X104001D01*
G01X95000Y154182D02*
X104000D01*
G01X95000D02*
X104000D01*
G01X94974Y152981D02*
X104001D01*
G01X95440Y143533D02*
X97900D01*
G01X95376Y144734D02*
X97901D01*
G01X95376D02*
X97901D01*
G01X95440Y143533D02*
X97900D01*
G01X72000Y130559D02*
X69000D01*
G01X72000Y129358D02*
X68999D01*
G01X72000D02*
X68999D01*
G01X72000Y130559D02*
X69000D01*
G01X109067Y163632D02*
X95000D01*
G01X108569Y162431D02*
X95000D01*
G01X112500Y160199D02*
X109067Y163632D01*
G01X111299Y159701D02*
X108569Y162431D01*
G01X111299Y144797D02*
Y159701D01*
G01X110297Y142096D02*
X112500Y144299D01*
G01X109096Y142594D02*
X111299Y144797D01*
G01X108569Y162431D02*
X95000D01*
G01X109067Y163632D02*
X95000D01*
G01X111299Y159701D02*
X108569Y162431D01*
G01X112500Y160199D02*
X109067Y163632D01*
G01X111299Y144797D02*
Y159701D01*
G01X109096Y142594D02*
X111299Y144797D01*
G01X110297Y142096D02*
X112500Y144299D01*
G01X94974Y152981D02*
X104001D01*
G01X95000Y154182D02*
X104000D01*
G01X95000D02*
X104000D01*
G01X94974Y152981D02*
X104001D01*
G01X62499Y392001D02*
X181802D01*
G01X62001Y390800D02*
X182300D01*
G01X56043Y398457D02*
X62499Y392001D01*
G01X54842Y397959D02*
X62001Y390800D01*
G01X56043Y778732D02*
Y398457D01*
G01X54842Y778234D02*
Y397959D01*
G01X62001Y390800D02*
X182300D01*
G01X62499Y392001D02*
X181802D01*
G01X54842Y397959D02*
X62001Y390800D01*
G01X56043Y398457D02*
X62499Y392001D01*
G01X54842Y778234D02*
Y397959D01*
G01X56043Y778732D02*
Y398457D01*
G01X62499Y392001D02*
X181802D01*
G01X62001Y390800D02*
X182300D01*
G01X56043Y398457D02*
X62499Y392001D01*
G01X54842Y397959D02*
X62001Y390800D01*
G01X56043Y778732D02*
Y398457D01*
G01X54842Y778234D02*
Y397959D01*
G01X62499Y392001D02*
X181802D01*
G01X62001Y390800D02*
X182300D01*
G01X56043Y398457D02*
X62499Y392001D01*
G01X54842Y397959D02*
X62001Y390800D01*
G01X56043Y778732D02*
Y398457D01*
G01X54842Y778234D02*
Y397959D01*
G01X62001Y390800D02*
X182300D01*
G01X62499Y392001D02*
X181802D01*
G01X54842Y397959D02*
X62001Y390800D01*
G01X56043Y398457D02*
X62499Y392001D01*
G01X54842Y778234D02*
Y397959D01*
G01X56043Y778732D02*
Y398457D01*
G01X62001Y390800D02*
X182300D01*
G01X62499Y392001D02*
X181802D01*
G01X54842Y397959D02*
X62001Y390800D01*
G01X56043Y398457D02*
X62499Y392001D01*
G01X54842Y778234D02*
Y397959D01*
G01X56043Y778732D02*
Y398457D01*
G01X62499Y392001D02*
X181802D01*
G01X62001Y390800D02*
X182300D01*
G01X56043Y398457D02*
X62499Y392001D01*
G01X54842Y397959D02*
X62001Y390800D01*
G01X56043Y778732D02*
Y398457D01*
G01X54842Y778234D02*
Y397959D01*
G01X62001Y390800D02*
X182300D01*
G01X62499Y392001D02*
X181802D01*
G01X54842Y397959D02*
X62001Y390800D01*
G01X56043Y398457D02*
X62499Y392001D01*
G01X54842Y778234D02*
Y397959D01*
G01X56043Y778732D02*
Y398457D01*
G01X94974Y470304D02*
X104001D01*
G01X95000Y471505D02*
X104000D01*
G01X95000D02*
X104000D01*
G01X94974Y470304D02*
X104001D01*
G01X95540Y460856D02*
X97900D01*
G01X95493Y462057D02*
X97901D01*
G01X95493D02*
X97901D01*
G01X95540Y460856D02*
X97900D01*
G01X95738Y479753D02*
X97901D01*
G01X95586Y480954D02*
X97900D01*
G01X95586D02*
X97900D01*
G01X95738Y479753D02*
X97901D01*
G01X94974Y470304D02*
X104001D01*
G01X95000Y471505D02*
X104000D01*
G01X95000D02*
X104000D01*
G01X94974Y470304D02*
X104001D01*
G01X72000Y536071D02*
X69000D01*
G01X72000Y534870D02*
X68999D01*
G01X72000D02*
X68999D01*
G01X72000Y536071D02*
X69000D01*
G01X111299Y553812D02*
Y565002D01*
G01Y548678D02*
Y550742D01*
G01Y543544D02*
Y545608D01*
G01Y528002D02*
Y540474D01*
G01X112758Y526543D02*
X111299Y528002D01*
G01X95000Y489202D02*
X104001D01*
G01X95097Y490403D02*
X104000D01*
G01X95097D02*
X104000D01*
G01X95000Y489202D02*
X104001D01*
G01X94974Y508100D02*
X104000D01*
G01X95000Y509301D02*
X104001D01*
G01X95000D02*
X104001D01*
G01X94974Y508100D02*
X104000D01*
G01X95390Y498651D02*
X97901D01*
G01X95348Y499852D02*
X97900D01*
G01X95348D02*
X97900D01*
G01X95390Y498651D02*
X97901D01*
G01X98046Y548899D02*
X94899D01*
G01X97755Y550100D02*
X95146D01*
G01X97755D02*
X95146D01*
G01X98046Y548899D02*
X94899D01*
G01X72000Y536071D02*
X69000D01*
G01X72000Y534870D02*
X68999D01*
G01X72000D02*
X68999D01*
G01X72000Y536071D02*
X69000D01*
G01X111299Y553812D02*
Y565002D01*
G01Y548678D02*
Y550742D01*
G01Y543544D02*
Y545608D01*
G01Y528002D02*
Y540474D01*
G01X112758Y526543D02*
X111299Y528002D01*
G01X95000Y489202D02*
X104001D01*
G01X95097Y490403D02*
X104000D01*
G01X95097D02*
X104000D01*
G01X95000Y489202D02*
X104001D01*
G01X94974Y508100D02*
X104000D01*
G01X95000Y509301D02*
X104001D01*
G01X95000D02*
X104001D01*
G01X94974Y508100D02*
X104000D01*
G01X95591Y558493D02*
X104001D01*
G01X95646Y559694D02*
X104000D01*
G01X95646D02*
X104000D01*
G01X95591Y558493D02*
X104001D01*
G01X108856Y569144D02*
X94974D01*
G01X108358Y567943D02*
X94975D01*
G01X112500Y565500D02*
X108856Y569144D01*
G01X111299Y565002D02*
X108358Y567943D01*
G01D02*
X94975D01*
G01X108856Y569144D02*
X94974D01*
G01X111299Y565002D02*
X108358Y567943D01*
G01X112500Y565500D02*
X108856Y569144D01*
G01X95591Y558493D02*
X104001D01*
G01X95646Y559694D02*
X104000D01*
G01X95646D02*
X104000D01*
G01X95591Y558493D02*
X104001D01*
G01X56700Y810900D02*
Y1052436D01*
G01X55499Y810402D02*
Y1052934D01*
G01X69999Y797601D02*
X56700Y810900D01*
G01X69501Y796400D02*
X55499Y810402D01*
G01X159101Y797601D02*
X69999D01*
G01X159599Y796400D02*
X69501D01*
G01X55499Y810402D02*
Y1052934D01*
G01X56700Y810900D02*
Y1052436D01*
G01X69501Y796400D02*
X55499Y810402D01*
G01X69999Y797601D02*
X56700Y810900D01*
G01X159599Y796400D02*
X69501D01*
G01X159101Y797601D02*
X69999D01*
G01X42639Y792136D02*
X56043Y778732D01*
G01X41438Y791638D02*
X54842Y778234D01*
G01X42639Y989060D02*
Y792136D01*
G01X41438Y988562D02*
Y791638D01*
G01D02*
X54842Y778234D01*
G01X42639Y792136D02*
X56043Y778732D01*
G01X41438Y988562D02*
Y791638D01*
G01X42639Y989060D02*
Y792136D01*
G01X56700Y810900D02*
Y1052436D01*
G01X55499Y810402D02*
Y1052934D01*
G01X69999Y797601D02*
X56700Y810900D01*
G01X69501Y796400D02*
X55499Y810402D01*
G01X159101Y797601D02*
X69999D01*
G01X159599Y796400D02*
X69501D01*
G01X56700Y810900D02*
Y1052436D01*
G01X55499Y810402D02*
Y1052934D01*
G01X69999Y797601D02*
X56700Y810900D01*
G01X69501Y796400D02*
X55499Y810402D01*
G01X159101Y797601D02*
X69999D01*
G01X159599Y796400D02*
X69501D01*
G01X55499Y810402D02*
Y1052934D01*
G01X56700Y810900D02*
Y1052436D01*
G01X69501Y796400D02*
X55499Y810402D01*
G01X69999Y797601D02*
X56700Y810900D01*
G01X159599Y796400D02*
X69501D01*
G01X159101Y797601D02*
X69999D01*
G01X55499Y810402D02*
Y1052934D01*
G01X56700Y810900D02*
Y1052436D01*
G01X69501Y796400D02*
X55499Y810402D01*
G01X69999Y797601D02*
X56700Y810900D01*
G01X159599Y796400D02*
X69501D01*
G01X159101Y797601D02*
X69999D01*
G01X42639Y792136D02*
X56043Y778732D01*
G01X41438Y791638D02*
X54842Y778234D01*
G01X42639Y989060D02*
Y792136D01*
G01X41438Y988562D02*
Y791638D01*
G01X42639Y792136D02*
X56043Y778732D01*
G01X41438Y791638D02*
X54842Y778234D01*
G01X42639Y989060D02*
Y792136D01*
G01X41438Y988562D02*
Y791638D01*
G01D02*
X54842Y778234D01*
G01X42639Y792136D02*
X56043Y778732D01*
G01X41438Y988562D02*
Y791638D01*
G01X42639Y989060D02*
Y792136D01*
G01X41438Y791638D02*
X54842Y778234D01*
G01X42639Y792136D02*
X56043Y778732D01*
G01X41438Y988562D02*
Y791638D01*
G01X42639Y989060D02*
Y792136D01*
G01X56700Y810900D02*
Y1052436D01*
G01X55499Y810402D02*
Y1052934D01*
G01X69999Y797601D02*
X56700Y810900D01*
G01X69501Y796400D02*
X55499Y810402D01*
G01X159101Y797601D02*
X69999D01*
G01X159599Y796400D02*
X69501D01*
G01X55499Y810402D02*
Y1052934D01*
G01X56700Y810900D02*
Y1052436D01*
G01X69501Y796400D02*
X55499Y810402D01*
G01X69999Y797601D02*
X56700Y810900D01*
G01X159599Y796400D02*
X69501D01*
G01X159101Y797601D02*
X69999D01*
G01X42639Y792136D02*
X56043Y778732D01*
G01X41438Y791638D02*
X54842Y778234D01*
G01X42639Y989060D02*
Y792136D01*
G01X41438Y988562D02*
Y791638D01*
G01D02*
X54842Y778234D01*
G01X42639Y792136D02*
X56043Y778732D01*
G01X41438Y988562D02*
Y791638D01*
G01X42639Y989060D02*
Y792136D01*
G01X94816Y875816D02*
X104001D01*
G01X94975Y877017D02*
X104000D01*
G01X94975D02*
X104000D01*
G01X94816Y875816D02*
X104001D01*
G01X94974Y894714D02*
X104001D01*
G01X94975Y895915D02*
X104000D01*
G01X94975D02*
X104000D01*
G01X94974Y894714D02*
X104001D01*
G01X94974Y913612D02*
X104000D01*
G01X95000Y914813D02*
X104001D01*
G01X95000D02*
X104001D01*
G01X94974Y913612D02*
X104000D01*
G01X94974Y866368D02*
X97900D01*
G01X95000Y867569D02*
X97901D01*
G01X95000D02*
X97901D01*
G01X94974Y866368D02*
X97900D01*
G01X94974Y885265D02*
X97901D01*
G01X95034Y886466D02*
X97900D01*
G01X95034D02*
X97900D01*
G01X94974Y885265D02*
X97901D01*
G01X94974Y904163D02*
X97901D01*
G01X95000Y905364D02*
X97900D01*
G01X95000D02*
X97900D01*
G01X94974Y904163D02*
X97901D01*
G01X94816Y875816D02*
X104001D01*
G01X94975Y877017D02*
X104000D01*
G01X94975D02*
X104000D01*
G01X94816Y875816D02*
X104001D01*
G01X94974Y894714D02*
X104001D01*
G01X94975Y895915D02*
X104000D01*
G01X94975D02*
X104000D01*
G01X94974Y894714D02*
X104001D01*
G01X94974Y913612D02*
X104000D01*
G01X95000Y914813D02*
X104001D01*
G01X95000D02*
X104001D01*
G01X94974Y913612D02*
X104000D01*
G01X72000Y941583D02*
X69000D01*
G01X72027Y940382D02*
X68999D01*
G01X72027D02*
X68999D01*
G01X72000Y941583D02*
X69000D01*
G01X94974Y964005D02*
X104001D01*
G01X95000Y965206D02*
X104000D01*
G01X95000D02*
X104000D01*
G01X94974Y964005D02*
X104001D01*
G01X94974Y954557D02*
X97900D01*
G01X95242Y955758D02*
X97901D01*
G01X95242D02*
X97901D01*
G01X94974Y954557D02*
X97900D01*
G01X72000Y941583D02*
X69000D01*
G01X72027Y940382D02*
X68999D01*
G01X72027D02*
X68999D01*
G01X72000Y941583D02*
X69000D01*
G01X108844Y974656D02*
X95000D01*
G01X108346Y973455D02*
X95000D01*
G01X162000Y921500D02*
X108844Y974656D01*
G01X114925Y966876D02*
X108346Y973455D01*
G01D02*
X95000D01*
G01X108844Y974656D02*
X95000D01*
G01X114925Y966876D02*
X108346Y973455D01*
G01X162000Y921500D02*
X108844Y974656D01*
G01X162000Y921500D02*
X108844Y974656D01*
G01X162000Y921500D02*
X108844Y974656D01*
G01X162000Y921500D02*
X108844Y974656D01*
G01X162000Y921500D02*
X108844Y974656D01*
G01X162000Y921500D02*
X108844Y974656D01*
G01X162000Y921500D02*
X108844Y974656D01*
G01X162000Y921500D02*
X108844Y974656D01*
G01X162000Y921500D02*
X108844Y974656D01*
G01X162000Y921500D02*
X108844Y974656D01*
G01X162000Y921500D02*
X108844Y974656D01*
G01X94974Y964005D02*
X104001D01*
G01X95000Y965206D02*
X104000D01*
G01X95000D02*
X104000D01*
G01X94974Y964005D02*
X104001D01*
G01X59500Y1055236D02*
Y1186001D01*
G01X58299Y1055734D02*
Y1185503D01*
G01X56700Y1052436D02*
X59500Y1055236D01*
G01X55499Y1052934D02*
X58299Y1055734D01*
G01D02*
Y1185503D01*
G01X59500Y1055236D02*
Y1186001D01*
G01X55499Y1052934D02*
X58299Y1055734D01*
G01X56700Y1052436D02*
X59500Y1055236D01*
G01X54011Y1057511D02*
X47500Y1051000D01*
G01X52810Y1058009D02*
X47002Y1052201D01*
G01X54011Y1181960D02*
Y1057511D01*
G01X52810Y1181462D02*
Y1058009D01*
G01D02*
X47002Y1052201D01*
G01X54011Y1057511D02*
X47500Y1051000D01*
G01X52810Y1181462D02*
Y1058009D01*
G01X54011Y1181960D02*
Y1057511D01*
G01X59500Y1055236D02*
Y1186001D01*
G01X58299Y1055734D02*
Y1185503D01*
G01X56700Y1052436D02*
X59500Y1055236D01*
G01X55499Y1052934D02*
X58299Y1055734D01*
G01X59500Y1055236D02*
Y1186001D01*
G01X58299Y1055734D02*
Y1185503D01*
G01X56700Y1052436D02*
X59500Y1055236D01*
G01X55499Y1052934D02*
X58299Y1055734D01*
G01D02*
Y1185503D01*
G01X59500Y1055236D02*
Y1186001D01*
G01X55499Y1052934D02*
X58299Y1055734D01*
G01X56700Y1052436D02*
X59500Y1055236D01*
G01X58299Y1055734D02*
Y1185503D01*
G01X59500Y1055236D02*
Y1186001D01*
G01X55499Y1052934D02*
X58299Y1055734D01*
G01X56700Y1052436D02*
X59500Y1055236D01*
G01X54011Y1057511D02*
X47500Y1051000D01*
G01X52810Y1058009D02*
X47002Y1052201D01*
G01X54011Y1181960D02*
Y1057511D01*
G01X52810Y1181462D02*
Y1058009D01*
G01X54011Y1057511D02*
X47500Y1051000D01*
G01X52810Y1058009D02*
X47002Y1052201D01*
G01X54011Y1181960D02*
Y1057511D01*
G01X52810Y1181462D02*
Y1058009D01*
G01D02*
X47002Y1052201D01*
G01X54011Y1057511D02*
X47500Y1051000D01*
G01X52810Y1181462D02*
Y1058009D01*
G01X54011Y1181960D02*
Y1057511D01*
G01X52810Y1058009D02*
X47002Y1052201D01*
G01X54011Y1057511D02*
X47500Y1051000D01*
G01X52810Y1181462D02*
Y1058009D01*
G01X54011Y1181960D02*
Y1057511D01*
G01X59500Y1055236D02*
Y1186001D01*
G01X58299Y1055734D02*
Y1185503D01*
G01X56700Y1052436D02*
X59500Y1055236D01*
G01X55499Y1052934D02*
X58299Y1055734D01*
G01D02*
Y1185503D01*
G01X59500Y1055236D02*
Y1186001D01*
G01X55499Y1052934D02*
X58299Y1055734D01*
G01X56700Y1052436D02*
X59500Y1055236D01*
G01X54011Y1057511D02*
X47500Y1051000D01*
G01X52810Y1058009D02*
X47002Y1052201D01*
G01X54011Y1181960D02*
Y1057511D01*
G01X52810Y1181462D02*
Y1058009D01*
G01D02*
X47002Y1052201D01*
G01X54011Y1057511D02*
X47500Y1051000D01*
G01X52810Y1181462D02*
Y1058009D01*
G01X54011Y1181960D02*
Y1057511D01*
G01X64199Y1203401D02*
X297199D01*
G01X63701Y1202200D02*
X296701D01*
G01X60056Y1207544D02*
X64199Y1203401D01*
G01X58855Y1207046D02*
X63701Y1202200D01*
G01X60056Y1289085D02*
Y1207544D01*
G01X58855Y1288587D02*
Y1207046D01*
G01X63701Y1202200D02*
X296701D01*
G01X64199Y1203401D02*
X297199D01*
G01X58855Y1207046D02*
X63701Y1202200D01*
G01X60056Y1207544D02*
X64199Y1203401D01*
G01X58855Y1288587D02*
Y1207046D01*
G01X60056Y1289085D02*
Y1207544D01*
G01X54567Y1190934D02*
Y1286810D01*
G01X53366Y1190436D02*
Y1286312D01*
G01X59500Y1186001D02*
X54567Y1190934D01*
G01X58299Y1185503D02*
X53366Y1190436D01*
G01D02*
Y1286312D01*
G01X54567Y1190934D02*
Y1286810D01*
G01X58299Y1185503D02*
X53366Y1190436D01*
G01X59500Y1186001D02*
X54567Y1190934D01*
G01X49078Y1186893D02*
X54011Y1181960D01*
G01X47877Y1186395D02*
X52810Y1181462D01*
G01X49078Y1284422D02*
Y1186893D01*
G01X47877Y1283924D02*
Y1186395D01*
G01D02*
X52810Y1181462D01*
G01X49078Y1186893D02*
X54011Y1181960D01*
G01X47877Y1283924D02*
Y1186395D01*
G01X49078Y1284422D02*
Y1186893D01*
G01X64199Y1203401D02*
X297199D01*
G01X63701Y1202200D02*
X296701D01*
G01X60056Y1207544D02*
X64199Y1203401D01*
G01X58855Y1207046D02*
X63701Y1202200D01*
G01X60056Y1289085D02*
Y1207544D01*
G01X58855Y1288587D02*
Y1207046D01*
G01X64199Y1203401D02*
X297199D01*
G01X63701Y1202200D02*
X296701D01*
G01X60056Y1207544D02*
X64199Y1203401D01*
G01X58855Y1207046D02*
X63701Y1202200D01*
G01X60056Y1289085D02*
Y1207544D01*
G01X58855Y1288587D02*
Y1207046D01*
G01X63701Y1202200D02*
X296701D01*
G01X64199Y1203401D02*
X297199D01*
G01X58855Y1207046D02*
X63701Y1202200D01*
G01X60056Y1207544D02*
X64199Y1203401D01*
G01X58855Y1288587D02*
Y1207046D01*
G01X60056Y1289085D02*
Y1207544D01*
G01X63701Y1202200D02*
X296701D01*
G01X64199Y1203401D02*
X297199D01*
G01X58855Y1207046D02*
X63701Y1202200D01*
G01X60056Y1207544D02*
X64199Y1203401D01*
G01X58855Y1288587D02*
Y1207046D01*
G01X60056Y1289085D02*
Y1207544D01*
G01X54567Y1190934D02*
Y1286810D01*
G01X53366Y1190436D02*
Y1286312D01*
G01X59500Y1186001D02*
X54567Y1190934D01*
G01X58299Y1185503D02*
X53366Y1190436D01*
G01X54567Y1190934D02*
Y1286810D01*
G01X53366Y1190436D02*
Y1286312D01*
G01X59500Y1186001D02*
X54567Y1190934D01*
G01X58299Y1185503D02*
X53366Y1190436D01*
G01D02*
Y1286312D01*
G01X54567Y1190934D02*
Y1286810D01*
G01X58299Y1185503D02*
X53366Y1190436D01*
G01X59500Y1186001D02*
X54567Y1190934D01*
G01X53366Y1190436D02*
Y1286312D01*
G01X54567Y1190934D02*
Y1286810D01*
G01X58299Y1185503D02*
X53366Y1190436D01*
G01X59500Y1186001D02*
X54567Y1190934D01*
G01X49078Y1186893D02*
X54011Y1181960D01*
G01X47877Y1186395D02*
X52810Y1181462D01*
G01X49078Y1284422D02*
Y1186893D01*
G01X47877Y1283924D02*
Y1186395D01*
G01X49078Y1186893D02*
X54011Y1181960D01*
G01X47877Y1186395D02*
X52810Y1181462D01*
G01X49078Y1284422D02*
Y1186893D01*
G01X47877Y1283924D02*
Y1186395D01*
G01D02*
X52810Y1181462D01*
G01X49078Y1186893D02*
X54011Y1181960D01*
G01X47877Y1283924D02*
Y1186395D01*
G01X49078Y1284422D02*
Y1186893D01*
G01X47877Y1186395D02*
X52810Y1181462D01*
G01X49078Y1186893D02*
X54011Y1181960D01*
G01X47877Y1283924D02*
Y1186395D01*
G01X49078Y1284422D02*
Y1186893D01*
G01X64199Y1203401D02*
X297199D01*
G01X63701Y1202200D02*
X296701D01*
G01X60056Y1207544D02*
X64199Y1203401D01*
G01X58855Y1207046D02*
X63701Y1202200D01*
G01X60056Y1289085D02*
Y1207544D01*
G01X58855Y1288587D02*
Y1207046D01*
G01X63701Y1202200D02*
X296701D01*
G01X64199Y1203401D02*
X297199D01*
G01X58855Y1207046D02*
X63701Y1202200D01*
G01X60056Y1207544D02*
X64199Y1203401D01*
G01X58855Y1288587D02*
Y1207046D01*
G01X60056Y1289085D02*
Y1207544D01*
G01X54567Y1190934D02*
Y1286810D01*
G01X53366Y1190436D02*
Y1286312D01*
G01X59500Y1186001D02*
X54567Y1190934D01*
G01X58299Y1185503D02*
X53366Y1190436D01*
G01D02*
Y1286312D01*
G01X54567Y1190934D02*
Y1286810D01*
G01X58299Y1185503D02*
X53366Y1190436D01*
G01X59500Y1186001D02*
X54567Y1190934D01*
G01X49078Y1186893D02*
X54011Y1181960D01*
G01X47877Y1186395D02*
X52810Y1181462D01*
G01X49078Y1284422D02*
Y1186893D01*
G01X47877Y1283924D02*
Y1186395D01*
G01D02*
X52810Y1181462D01*
G01X49078Y1186893D02*
X54011Y1181960D01*
G01X47877Y1283924D02*
Y1186395D01*
G01X49078Y1284422D02*
Y1186893D01*
G01X44511Y1288989D02*
X49078Y1284422D01*
G01X43310Y1288491D02*
X47877Y1283924D01*
G01X43310Y1288491D02*
X47877Y1283924D01*
G01X44511Y1288989D02*
X49078Y1284422D01*
G01X44511Y1288989D02*
X49078Y1284422D01*
G01X43310Y1288491D02*
X47877Y1283924D01*
G01X44511Y1288989D02*
X49078Y1284422D01*
G01X43310Y1288491D02*
X47877Y1283924D01*
G01X43310Y1288491D02*
X47877Y1283924D01*
G01X44511Y1288989D02*
X49078Y1284422D01*
G01X43310Y1288491D02*
X47877Y1283924D01*
G01X44511Y1288989D02*
X49078Y1284422D01*
G01X94974Y1281328D02*
X104001D01*
G01X95000Y1282529D02*
X104000D01*
G01X95000D02*
X104000D01*
G01X94974Y1281328D02*
X104001D01*
G01X97938Y1271842D02*
X94936D01*
G01X97863Y1273043D02*
X95038D01*
G01X97863D02*
X95038D01*
G01X97938Y1271842D02*
X94936D01*
G01X94974Y1281328D02*
X104001D01*
G01X95000Y1282529D02*
X104000D01*
G01X95000D02*
X104000D01*
G01X94974Y1281328D02*
X104001D01*
G01X44511Y1288989D02*
X49078Y1284422D01*
G01X43310Y1288491D02*
X47877Y1283924D01*
G01X43310Y1288491D02*
X47877Y1283924D01*
G01X44511Y1288989D02*
X49078Y1284422D01*
G01X55543Y1293598D02*
X60056Y1289085D01*
G01X54342Y1293100D02*
X58855Y1288587D01*
G01X55543Y1473044D02*
Y1293598D01*
G01X54342Y1473542D02*
Y1293100D01*
G01D02*
X58855Y1288587D01*
G01X55543Y1293598D02*
X60056Y1289085D01*
G01X54342Y1473542D02*
Y1293100D01*
G01X55543Y1473044D02*
Y1293598D01*
G01X50000Y1291377D02*
Y1470699D01*
G01X48799Y1290879D02*
Y1470201D01*
G01X54567Y1286810D02*
X50000Y1291377D01*
G01X53366Y1286312D02*
X48799Y1290879D01*
G01D02*
Y1470201D01*
G01X50000Y1291377D02*
Y1470699D01*
G01X53366Y1286312D02*
X48799Y1290879D01*
G01X54567Y1286810D02*
X50000Y1291377D01*
G01X44511Y1465489D02*
Y1288989D01*
G01X43310Y1464991D02*
Y1288491D01*
G01Y1464991D02*
Y1288491D01*
G01X44511Y1465489D02*
Y1288989D01*
G01X55543Y1293598D02*
X60056Y1289085D01*
G01X54342Y1293100D02*
X58855Y1288587D01*
G01X55543Y1473044D02*
Y1293598D01*
G01X54342Y1473542D02*
Y1293100D01*
G01X55543Y1293598D02*
X60056Y1289085D01*
G01X54342Y1293100D02*
X58855Y1288587D01*
G01X55543Y1473044D02*
Y1293598D01*
G01X54342Y1473542D02*
Y1293100D01*
G01D02*
X58855Y1288587D01*
G01X55543Y1293598D02*
X60056Y1289085D01*
G01X54342Y1473542D02*
Y1293100D01*
G01X55543Y1473044D02*
Y1293598D01*
G01X54342Y1293100D02*
X58855Y1288587D01*
G01X55543Y1293598D02*
X60056Y1289085D01*
G01X54342Y1473542D02*
Y1293100D01*
G01X55543Y1473044D02*
Y1293598D01*
G01X50000Y1291377D02*
Y1470699D01*
G01X48799Y1290879D02*
Y1470201D01*
G01X54567Y1286810D02*
X50000Y1291377D01*
G01X53366Y1286312D02*
X48799Y1290879D01*
G01X50000Y1291377D02*
Y1470699D01*
G01X48799Y1290879D02*
Y1470201D01*
G01X54567Y1286810D02*
X50000Y1291377D01*
G01X53366Y1286312D02*
X48799Y1290879D01*
G01D02*
Y1470201D01*
G01X50000Y1291377D02*
Y1470699D01*
G01X53366Y1286312D02*
X48799Y1290879D01*
G01X54567Y1286810D02*
X50000Y1291377D01*
G01X48799Y1290879D02*
Y1470201D01*
G01X50000Y1291377D02*
Y1470699D01*
G01X53366Y1286312D02*
X48799Y1290879D01*
G01X54567Y1286810D02*
X50000Y1291377D01*
G01X44511Y1465489D02*
Y1288989D01*
G01X43310Y1464991D02*
Y1288491D01*
G01X44511Y1465489D02*
Y1288989D01*
G01X43310Y1464991D02*
Y1288491D01*
G01Y1464991D02*
Y1288491D01*
G01X44511Y1465489D02*
Y1288989D01*
G01X43310Y1464991D02*
Y1288491D01*
G01X44511Y1465489D02*
Y1288989D01*
G01X72000Y1347095D02*
X69000D01*
G01X72027Y1345894D02*
X68999D01*
G01X72027D02*
X68999D01*
G01X72000Y1347095D02*
X69000D01*
G01X94974Y1300226D02*
X104001D01*
G01X95000Y1301427D02*
X104000D01*
G01X95000D02*
X104000D01*
G01X94974Y1300226D02*
X104001D01*
G01X94974Y1319124D02*
X104000D01*
G01X95000Y1320325D02*
X104001D01*
G01X95000D02*
X104001D01*
G01X94974Y1319124D02*
X104000D01*
G01X97949Y1290729D02*
X94926D01*
G01X97852Y1291930D02*
X95070D01*
G01X97852D02*
X95070D01*
G01X97949Y1290729D02*
X94926D01*
G01X95450Y1309675D02*
X97901D01*
G01X95454Y1310876D02*
X97900D01*
G01X95454D02*
X97900D01*
G01X95450Y1309675D02*
X97901D01*
G01X72000Y1347095D02*
X69000D01*
G01X72027Y1345894D02*
X68999D01*
G01X72027D02*
X68999D01*
G01X72000Y1347095D02*
X69000D01*
G01X55543Y1293598D02*
X60056Y1289085D01*
G01X54342Y1293100D02*
X58855Y1288587D01*
G01X55543Y1473044D02*
Y1293598D01*
G01X54342Y1473542D02*
Y1293100D01*
G01D02*
X58855Y1288587D01*
G01X55543Y1293598D02*
X60056Y1289085D01*
G01X54342Y1473542D02*
Y1293100D01*
G01X55543Y1473044D02*
Y1293598D01*
G01X50000Y1291377D02*
Y1470699D01*
G01X48799Y1290879D02*
Y1470201D01*
G01X54567Y1286810D02*
X50000Y1291377D01*
G01X53366Y1286312D02*
X48799Y1290879D01*
G01D02*
Y1470201D01*
G01X50000Y1291377D02*
Y1470699D01*
G01X53366Y1286312D02*
X48799Y1290879D01*
G01X54567Y1286810D02*
X50000Y1291377D01*
G01X94974Y1300226D02*
X104001D01*
G01X95000Y1301427D02*
X104000D01*
G01X95000D02*
X104000D01*
G01X94974Y1300226D02*
X104001D01*
G01X94974Y1319124D02*
X104000D01*
G01X95000Y1320325D02*
X104001D01*
G01X95000D02*
X104001D01*
G01X94974Y1319124D02*
X104000D01*
G01X44511Y1465489D02*
Y1288989D01*
G01X43310Y1464991D02*
Y1288491D01*
G01Y1464991D02*
Y1288491D01*
G01X44511Y1465489D02*
Y1288989D01*
G01X94974Y1369517D02*
X104001D01*
G01X95000Y1370718D02*
X104000D01*
G01X95000D02*
X104000D01*
G01X94974Y1369517D02*
X104001D01*
G01X97870Y1360099D02*
X95004D01*
G01X97931Y1361300D02*
X94944D01*
G01X97931D02*
X94944D01*
G01X97870Y1360099D02*
X95004D01*
G01X108531Y1380168D02*
X95332D01*
G01X108033Y1378967D02*
X95332D01*
G01X113701Y1374998D02*
X108531Y1380168D01*
G01X112500Y1374500D02*
X108033Y1378967D01*
G01D02*
X95332D01*
G01X108531Y1380168D02*
X95332D01*
G01X112500Y1374500D02*
X108033Y1378967D01*
G01X113701Y1374998D02*
X108531Y1380168D01*
G01X94974Y1369517D02*
X104001D01*
G01X95000Y1370718D02*
X104000D01*
G01X95000D02*
X104000D01*
G01X94974Y1369517D02*
X104001D01*
G01X57201Y1474702D02*
X55543Y1473044D01*
G01X56000Y1475200D02*
X54342Y1473542D01*
G01X57201Y1499440D02*
Y1474702D01*
G01X56000Y1673670D02*
Y1475200D01*
G01X57201Y1504574D02*
Y1502510D01*
G01X56000Y1673670D02*
Y1475200D01*
G01Y1673670D02*
Y1475200D01*
G01Y1673670D02*
Y1475200D01*
G01Y1673670D02*
Y1475200D01*
G01Y1673670D02*
Y1475200D01*
G01D02*
X54342Y1473542D01*
G01X57201Y1474702D02*
X55543Y1473044D01*
G01X56000Y1673670D02*
Y1475200D01*
G01X57201Y1499440D02*
Y1474702D01*
G01Y1504574D02*
Y1502510D01*
G01Y1474702D02*
X55543Y1473044D01*
G01X56000Y1475200D02*
X54342Y1473542D01*
G01X57201Y1499440D02*
Y1474702D01*
G01X56000Y1673670D02*
Y1475200D01*
G01X57201Y1504574D02*
Y1502510D01*
G01X56000Y1673670D02*
Y1475200D01*
G01Y1673670D02*
Y1475200D01*
G01Y1673670D02*
Y1475200D01*
G01Y1673670D02*
Y1475200D01*
G01Y1673670D02*
Y1475200D01*
G01X57201Y1474702D02*
X55543Y1473044D01*
G01X56000Y1475200D02*
X54342Y1473542D01*
G01X57201Y1499440D02*
Y1474702D01*
G01X56000Y1673670D02*
Y1475200D01*
G01X57201Y1504574D02*
Y1502510D01*
G01X56000Y1673670D02*
Y1475200D01*
G01Y1673670D02*
Y1475200D01*
G01Y1673670D02*
Y1475200D01*
G01Y1673670D02*
Y1475200D01*
G01Y1673670D02*
Y1475200D01*
G01D02*
X54342Y1473542D01*
G01X57201Y1474702D02*
X55543Y1473044D01*
G01X56000Y1673670D02*
Y1475200D01*
G01X57201Y1499440D02*
Y1474702D01*
G01Y1504574D02*
Y1502510D01*
G01X56000Y1475200D02*
X54342Y1473542D01*
G01X57201Y1474702D02*
X55543Y1473044D01*
G01X56000Y1673670D02*
Y1475200D01*
G01X57201Y1499440D02*
Y1474702D01*
G01Y1504574D02*
Y1502510D01*
G01Y1474702D02*
X55543Y1473044D01*
G01X56000Y1475200D02*
X54342Y1473542D01*
G01X57201Y1499440D02*
Y1474702D01*
G01X56000Y1673670D02*
Y1475200D01*
G01X57201Y1504574D02*
Y1502510D01*
G01X56000Y1673670D02*
Y1475200D01*
G01Y1673670D02*
Y1475200D01*
G01Y1673670D02*
Y1475200D01*
G01Y1673670D02*
Y1475200D01*
G01Y1673670D02*
Y1475200D01*
G01D02*
X54342Y1473542D01*
G01X57201Y1474702D02*
X55543Y1473044D01*
G01X56000Y1673670D02*
Y1475200D01*
G01X57201Y1499440D02*
Y1474702D01*
G01Y1504574D02*
Y1502510D01*
G01Y1594320D02*
Y1507644D01*
G01Y1594320D02*
Y1507644D01*
G01Y1594320D02*
Y1507644D01*
G01Y1594320D02*
Y1507644D01*
G01Y1594320D02*
Y1507644D01*
G01Y1594320D02*
Y1507644D01*
G01Y1594320D02*
Y1507644D01*
G01Y1594320D02*
Y1507644D01*
G01Y1599454D02*
Y1597390D01*
G01Y1604588D02*
Y1602524D01*
G01Y1673627D02*
Y1607658D01*
G01Y1599454D02*
Y1597390D01*
G01Y1604588D02*
Y1602524D01*
G01Y1673627D02*
Y1607658D01*
G01Y1599454D02*
Y1597390D01*
G01Y1604588D02*
Y1602524D01*
G01Y1673627D02*
Y1607658D01*
G01Y1599454D02*
Y1597390D01*
G01Y1604588D02*
Y1602524D01*
G01Y1673627D02*
Y1607658D01*
G01Y1599454D02*
Y1597390D01*
G01Y1604588D02*
Y1602524D01*
G01Y1673627D02*
Y1607658D01*
G01Y1599454D02*
Y1597390D01*
G01Y1604588D02*
Y1602524D01*
G01Y1673627D02*
Y1607658D01*
G01Y1599454D02*
Y1597390D01*
G01Y1604588D02*
Y1602524D01*
G01Y1673627D02*
Y1607658D01*
G01Y1599454D02*
Y1597390D01*
G01Y1604588D02*
Y1602524D01*
G01Y1673627D02*
Y1607658D01*
G01X104100Y1688141D02*
X94900D01*
G01X103901Y1686940D02*
X95074D01*
G01X103901D02*
X95074D01*
G01X104100Y1688141D02*
X94900D01*
G01X104100Y1707039D02*
X94875D01*
G01X103901Y1705838D02*
X95074D01*
G01X103901D02*
X95074D01*
G01X104100Y1707039D02*
X94875D01*
G01X94907Y1678593D02*
X97901D01*
G01X95000Y1677392D02*
X97900D01*
G01X95000D02*
X97900D01*
G01X94907Y1678593D02*
X97901D01*
G01X98000Y1697590D02*
X94900D01*
G01X97801Y1696389D02*
X95074D01*
G01X97801D02*
X95074D01*
G01X98000Y1697590D02*
X94900D01*
G01X94975Y1716388D02*
X97900D01*
G01X94974Y1715187D02*
X97901D01*
G01X94974D02*
X97901D01*
G01X94975Y1716388D02*
X97900D01*
G01X47500Y1707153D02*
Y1747500D01*
G01X46299Y1718391D02*
Y1720455D01*
G01Y1706655D02*
Y1715321D01*
G01X57201Y1697452D02*
X47500Y1707153D01*
G01X56000Y1696954D02*
X46299Y1706655D01*
G01X57201Y1679469D02*
Y1697452D01*
G01X56000Y1679426D02*
Y1696954D01*
G01X47500Y1707153D02*
Y1747500D01*
G01X46299Y1718391D02*
Y1720455D01*
G01X47500Y1707153D02*
Y1747500D01*
G01X46299Y1706655D02*
Y1715321D01*
G01X47500Y1707153D02*
Y1747500D01*
G01X56000Y1696954D02*
X46299Y1706655D01*
G01X57201Y1697452D02*
X47500Y1707153D01*
G01X56000Y1679426D02*
Y1696954D01*
G01X57201Y1679469D02*
Y1697452D01*
G01X104100Y1688141D02*
X94900D01*
G01X103901Y1686940D02*
X95074D01*
G01X103901D02*
X95074D01*
G01X104100Y1688141D02*
X94900D01*
G01X104100Y1707039D02*
X94875D01*
G01X103901Y1705838D02*
X95074D01*
G01X103901D02*
X95074D01*
G01X104100Y1707039D02*
X94875D01*
G01X44398Y1776499D02*
X72809Y1804910D01*
G01X43900Y1777700D02*
X72311Y1806111D01*
G01X44398Y1776499D02*
X72809Y1804910D01*
G01X43900Y1777700D02*
X72311Y1806111D01*
G01X44398Y1776499D02*
X72809Y1804910D01*
G01X43900Y1777700D02*
X72311Y1806111D01*
G01X44398Y1776499D02*
X72809Y1804910D01*
G01X43900Y1777700D02*
X72311Y1806111D01*
G01X43900Y1777700D02*
X72311Y1806111D01*
G01X44398Y1776499D02*
X72809Y1804910D01*
G01X43900Y1777700D02*
X72311Y1806111D01*
G01X44398Y1776499D02*
X72809Y1804910D01*
G01X43900Y1777700D02*
X72311Y1806111D01*
G01X44398Y1776499D02*
X72809Y1804910D01*
G01X43900Y1777700D02*
X72311Y1806111D01*
G01X44398Y1776499D02*
X72809Y1804910D01*
G01X71607Y1752607D02*
X69000D01*
G01X71500Y1751406D02*
X68999D01*
G01X71500D02*
X68999D01*
G01X71607Y1752607D02*
X69000D01*
G01X104101Y1725937D02*
X95374D01*
G01X103900Y1724736D02*
X95574D01*
G01X103900D02*
X95574D01*
G01X104101Y1725937D02*
X95374D01*
G01X104100Y1776330D02*
X95170D01*
G01X103901Y1775129D02*
X95129D01*
G01X103901D02*
X95129D01*
G01X104100Y1776330D02*
X95170D01*
G01X98001Y1766882D02*
X94900D01*
G01X97800Y1765681D02*
X95181D01*
G01X97800D02*
X95181D01*
G01X98001Y1766882D02*
X94900D01*
G01X71607Y1752607D02*
X69000D01*
G01X71500Y1751406D02*
X68999D01*
G01X71500D02*
X68999D01*
G01X71607Y1752607D02*
X69000D01*
G01X110019Y1785680D02*
X95000D01*
G01X109521Y1784479D02*
X94975D01*
G01X113201Y1782498D02*
X110019Y1785680D01*
G01X112000Y1782000D02*
X109521Y1784479D01*
G01D02*
X94975D01*
G01X110019Y1785680D02*
X95000D01*
G01X112000Y1782000D02*
X109521Y1784479D01*
G01X113201Y1782498D02*
X110019Y1785680D01*
G01X46299Y1747002D02*
X42453Y1750848D01*
G01X46299Y1723525D02*
Y1747002D01*
G01D02*
X42453Y1750848D01*
G01X46299Y1723525D02*
Y1747002D01*
G01X44398Y1776499D02*
X72809Y1804910D01*
G01X43900Y1777700D02*
X72311Y1806111D01*
G01X43900Y1777700D02*
X72311Y1806111D01*
G01X44398Y1776499D02*
X72809Y1804910D01*
G01X104101Y1725937D02*
X95374D01*
G01X103900Y1724736D02*
X95574D01*
G01X103900D02*
X95574D01*
G01X104101Y1725937D02*
X95374D01*
G01X104100Y1776330D02*
X95170D01*
G01X103901Y1775129D02*
X95129D01*
G01X103901D02*
X95129D01*
G01X104100Y1776330D02*
X95170D01*
G01X104751Y1809299D02*
X126638Y1787412D01*
G01X105249Y1810500D02*
X127839Y1787910D01*
G01X81634Y1809299D02*
X104751D01*
G01X81136Y1810500D02*
X105249D01*
G01X77245Y1804910D02*
X81634Y1809299D01*
G01X76747Y1806111D02*
X81136Y1810500D01*
G01X72809Y1804910D02*
X77245D01*
G01X72311Y1806111D02*
X76747D01*
G01X104751Y1809299D02*
X126638Y1787412D01*
G01X105249Y1810500D02*
X127839Y1787910D01*
G01X81634Y1809299D02*
X104751D01*
G01X81136Y1810500D02*
X105249D01*
G01X77245Y1804910D02*
X81634Y1809299D01*
G01X76747Y1806111D02*
X81136Y1810500D01*
G01X72809Y1804910D02*
X77245D01*
G01X72311Y1806111D02*
X76747D01*
G01X104751Y1809299D02*
X126638Y1787412D01*
G01X105249Y1810500D02*
X127839Y1787910D01*
G01X81634Y1809299D02*
X104751D01*
G01X81136Y1810500D02*
X105249D01*
G01X77245Y1804910D02*
X81634Y1809299D01*
G01X76747Y1806111D02*
X81136Y1810500D01*
G01X72809Y1804910D02*
X77245D01*
G01X72311Y1806111D02*
X76747D01*
G01X104751Y1809299D02*
X126638Y1787412D01*
G01X105249Y1810500D02*
X127839Y1787910D01*
G01X81634Y1809299D02*
X104751D01*
G01X81136Y1810500D02*
X105249D01*
G01X77245Y1804910D02*
X81634Y1809299D01*
G01X76747Y1806111D02*
X81136Y1810500D01*
G01X72809Y1804910D02*
X77245D01*
G01X72311Y1806111D02*
X76747D01*
G01X105249Y1810500D02*
X127839Y1787910D01*
G01X104751Y1809299D02*
X126638Y1787412D01*
G01X81136Y1810500D02*
X105249D01*
G01X81634Y1809299D02*
X104751D01*
G01X76747Y1806111D02*
X81136Y1810500D01*
G01X77245Y1804910D02*
X81634Y1809299D01*
G01X72311Y1806111D02*
X76747D01*
G01X72809Y1804910D02*
X77245D01*
G01X105249Y1810500D02*
X127839Y1787910D01*
G01X104751Y1809299D02*
X126638Y1787412D01*
G01X81136Y1810500D02*
X105249D01*
G01X81634Y1809299D02*
X104751D01*
G01X76747Y1806111D02*
X81136Y1810500D01*
G01X77245Y1804910D02*
X81634Y1809299D01*
G01X72311Y1806111D02*
X76747D01*
G01X72809Y1804910D02*
X77245D01*
G01X105249Y1810500D02*
X127839Y1787910D01*
G01X104751Y1809299D02*
X126638Y1787412D01*
G01X81136Y1810500D02*
X105249D01*
G01X81634Y1809299D02*
X104751D01*
G01X76747Y1806111D02*
X81136Y1810500D01*
G01X77245Y1804910D02*
X81634Y1809299D01*
G01X72311Y1806111D02*
X76747D01*
G01X72809Y1804910D02*
X77245D01*
G01X105249Y1810500D02*
X127839Y1787910D01*
G01X104751Y1809299D02*
X126638Y1787412D01*
G01X81136Y1810500D02*
X105249D01*
G01X81634Y1809299D02*
X104751D01*
G01X76747Y1806111D02*
X81136Y1810500D01*
G01X77245Y1804910D02*
X81634Y1809299D01*
G01X72311Y1806111D02*
X76747D01*
G01X72809Y1804910D02*
X77245D01*
G01X104751Y1809299D02*
X126638Y1787412D01*
G01X105249Y1810500D02*
X127839Y1787910D01*
G01X81634Y1809299D02*
X104751D01*
G01X81136Y1810500D02*
X105249D01*
G01X77245Y1804910D02*
X81634Y1809299D01*
G01X76747Y1806111D02*
X81136Y1810500D01*
G01X72809Y1804910D02*
X77245D01*
G01X72311Y1806111D02*
X76747D01*
G01X105249Y1810500D02*
X127839Y1787910D01*
G01X104751Y1809299D02*
X126638Y1787412D01*
G01X81136Y1810500D02*
X105249D01*
G01X81634Y1809299D02*
X104751D01*
G01X76747Y1806111D02*
X81136Y1810500D01*
G01X77245Y1804910D02*
X81634Y1809299D01*
G01X72311Y1806111D02*
X76747D01*
G01X72809Y1804910D02*
X77245D01*
G01X123439Y110901D02*
X118798D01*
G01X243200Y109700D02*
X118300D01*
G01X128573Y110901D02*
X126509D01*
G01X243200Y109700D02*
X118300D01*
G01X133707Y110901D02*
X131643D01*
G01X243200Y109700D02*
X118300D01*
G01X181632Y110901D02*
X136777D01*
G01X243200Y109700D02*
X118300D01*
G01X243200D02*
X118300D01*
G01X243200D02*
X118300D01*
G01X243200D02*
X118300D01*
G01X123439Y110901D02*
X118798D01*
G01X128573D02*
X126509D01*
G01X133707D02*
X131643D01*
G01X181632D02*
X136777D01*
G01X130520Y130561D02*
X124998D01*
G01X239559Y129360D02*
X125001D01*
G01X135654Y130561D02*
X133590D01*
G01X239559Y129360D02*
X125001D01*
G01X140788Y130561D02*
X138724D01*
G01X239559Y129360D02*
X125001D01*
G01X153858Y130561D02*
X143858D01*
G01X239559Y129360D02*
X125001D01*
G01X158992Y130561D02*
X156928D01*
G01X239559Y129360D02*
X125001D01*
G01X239061Y130561D02*
X162062D01*
G01X239559Y129360D02*
X125001D01*
G01X239559D02*
X125001D01*
G01X130520Y130561D02*
X124998D01*
G01X135654D02*
X133590D01*
G01X140788D02*
X138724D01*
G01X153858D02*
X143858D01*
G01X158992D02*
X156928D01*
G01X239061D02*
X162062D01*
G01X130520D02*
X124998D01*
G01X239559Y129360D02*
X125001D01*
G01X135654Y130561D02*
X133590D01*
G01X239559Y129360D02*
X125001D01*
G01X140788Y130561D02*
X138724D01*
G01X239559Y129360D02*
X125001D01*
G01X153858Y130561D02*
X143858D01*
G01X239559Y129360D02*
X125001D01*
G01X158992Y130561D02*
X156928D01*
G01X239559Y129360D02*
X125001D01*
G01X239061Y130561D02*
X162062D01*
G01X239559Y129360D02*
X125001D01*
G01X239559D02*
X125001D01*
G01X130520Y130561D02*
X124998D01*
G01X135654D02*
X133590D01*
G01X140788D02*
X138724D01*
G01X153858D02*
X143858D01*
G01X158992D02*
X156928D01*
G01X239061D02*
X162062D01*
G01X112500Y144299D02*
Y160199D01*
G01Y144299D02*
Y160199D01*
G01X177799Y238502D02*
Y236393D01*
G01X179000Y239000D02*
Y236394D01*
G01X176783Y239518D02*
X177799Y238502D01*
G01X177281Y240719D02*
X179000Y239000D01*
G01X171975Y239518D02*
X176783D01*
G01X172000Y240719D02*
X177281D01*
G01X179000Y239000D02*
Y236394D01*
G01X177799Y238502D02*
Y236393D01*
G01X177281Y240719D02*
X179000Y239000D01*
G01X176783Y239518D02*
X177799Y238502D01*
G01X172000Y240719D02*
X177281D01*
G01X171975Y239518D02*
X176783D01*
G01X149000Y217097D02*
X140094D01*
G01X149000Y215896D02*
X140095D01*
G01X149000D02*
X140095D01*
G01X149000Y217097D02*
X140094D01*
G01X149000Y226545D02*
X146195D01*
G01X149000Y225344D02*
X146194D01*
G01X149000D02*
X146194D01*
G01X149000Y226545D02*
X146195D01*
G01X177799Y238502D02*
Y236393D01*
G01X179000Y239000D02*
Y236394D01*
G01X176783Y239518D02*
X177799Y238502D01*
G01X177281Y240719D02*
X179000Y239000D01*
G01X171975Y239518D02*
X176783D01*
G01X172000Y240719D02*
X177281D01*
G01X179000Y239000D02*
Y236394D01*
G01X177799Y238502D02*
Y236393D01*
G01X177281Y240719D02*
X179000Y239000D01*
G01X176783Y239518D02*
X177799Y238502D01*
G01X172000Y240719D02*
X177281D01*
G01X171975Y239518D02*
X176783D01*
G01X147446Y206446D02*
X149000D01*
G01X146948Y207647D02*
X149000D01*
G01X144299Y204998D02*
X146948Y207647D01*
G01X145500Y204500D02*
X147446Y206446D01*
G01X144299Y204998D02*
X146948Y207647D01*
G01X145500Y201699D02*
Y204500D01*
G01X144299Y201201D02*
Y204998D01*
G01X147998Y199201D02*
X145500Y201699D01*
G01X147500Y198000D02*
X144299Y201201D01*
G01X179201Y199201D02*
X147998D01*
G01X179699Y198000D02*
X147500D01*
G01X180660Y200660D02*
X179201Y199201D01*
G01X205450Y223751D02*
X179699Y198000D01*
G01X184291Y204291D02*
X182831Y202831D01*
G01X205450Y223751D02*
X179699Y198000D01*
G01X205450Y223751D02*
X179699Y198000D01*
G01X205450Y223751D02*
X179699Y198000D01*
G01X205450Y223751D02*
X179699Y198000D01*
G01X146948Y207647D02*
X149000D01*
G01X147446Y206446D02*
X149000D01*
G01X144299Y204998D02*
X146948Y207647D01*
G01X147446Y206446D02*
X149000D01*
G01X145500Y204500D02*
X147446Y206446D01*
G01X144299Y201201D02*
Y204998D01*
G01X145500Y201699D02*
Y204500D01*
G01X147500Y198000D02*
X144299Y201201D01*
G01X147998Y199201D02*
X145500Y201699D01*
G01X179699Y198000D02*
X147500D01*
G01X179201Y199201D02*
X147998D01*
G01X205450Y223751D02*
X179699Y198000D01*
G01X180660Y200660D02*
X179201Y199201D01*
G01X184291Y204291D02*
X182831Y202831D01*
G01X149000Y217097D02*
X140094D01*
G01X149000Y215896D02*
X140095D01*
G01X149000D02*
X140095D01*
G01X149000Y217097D02*
X140094D01*
G01X149000Y305286D02*
X140094D01*
G01X149000Y304085D02*
X140095D01*
G01X149000D02*
X140095D01*
G01X149000Y305286D02*
X140094D01*
G01X149026Y286388D02*
X140094D01*
G01X149025Y285187D02*
X140095D01*
G01X149025D02*
X140095D01*
G01X149026Y286388D02*
X140094D01*
G01X148990Y267490D02*
X140095D01*
G01X149000Y266289D02*
X140094D01*
G01X149026Y314734D02*
X146195D01*
G01X149026Y313533D02*
X146194D01*
G01X149026D02*
X146194D01*
G01X149026Y314734D02*
X146195D01*
G01X149026Y295837D02*
X146194D01*
G01X149000Y294636D02*
X146195D01*
G01X149000D02*
X146195D01*
G01X149026Y295837D02*
X146194D01*
G01X149026Y276939D02*
X146194D01*
G01X149000Y275738D02*
X146195D01*
G01X149000D02*
X146195D01*
G01X149026Y276939D02*
X146194D01*
G01X149000Y266289D02*
X140094D01*
G01X148990Y267490D02*
X140095D01*
G01X149000Y305286D02*
X140094D01*
G01X149000Y304085D02*
X140095D01*
G01X149000D02*
X140095D01*
G01X149000Y305286D02*
X140094D01*
G01X149026Y286388D02*
X140094D01*
G01X149025Y285187D02*
X140095D01*
G01X149025D02*
X140095D01*
G01X149026Y286388D02*
X140094D01*
G01X148990Y267490D02*
X140095D01*
G01X149000Y266289D02*
X140094D01*
G01X149000D02*
X140094D01*
G01X148990Y267490D02*
X140095D01*
G01X181802Y392001D02*
X189002Y399201D01*
G01X182300Y390800D02*
X189500Y398000D01*
G01X182300Y390800D02*
X189500Y398000D01*
G01X181802Y392001D02*
X189002Y399201D01*
G01X181802Y392001D02*
X189002Y399201D01*
G01X182300Y390800D02*
X189500Y398000D01*
G01X181802Y392001D02*
X189002Y399201D01*
G01X182300Y390800D02*
X189500Y398000D01*
G01X182300Y390800D02*
X189500Y398000D01*
G01X181802Y392001D02*
X189002Y399201D01*
G01X182300Y390800D02*
X189500Y398000D01*
G01X181802Y392001D02*
X189002Y399201D01*
G01X181802Y392001D02*
X189002Y399201D01*
G01X182300Y390800D02*
X189500Y398000D01*
G01X182300Y390800D02*
X189500Y398000D01*
G01X181802Y392001D02*
X189002Y399201D01*
G01X130126Y536073D02*
X125000D01*
G01X129628Y534872D02*
X124999D01*
G01X165716Y500483D02*
X130126Y536073D01*
G01X132672Y531828D02*
X129628Y534872D01*
G01X134843Y529657D02*
X134131D01*
G01X136302Y528198D02*
X134843Y529657D01*
G01X138473Y526027D02*
X137762D01*
G01X139933Y524567D02*
X138473Y526027D01*
G01X142103Y522397D02*
X141392D01*
G01X149174Y515326D02*
X142103Y522397D01*
G01X151345Y513155D02*
X150634D01*
G01X152805Y511695D02*
X151345Y513155D01*
G01X154976Y509524D02*
X154264D01*
G01X165218Y499282D02*
X154976Y509524D01*
G01X326216Y500483D02*
X165716D01*
G01X325718Y499282D02*
X165218D01*
G01X129628Y534872D02*
X124999D01*
G01X130126Y536073D02*
X125000D01*
G01X132672Y531828D02*
X129628Y534872D01*
G01X165716Y500483D02*
X130126Y536073D01*
G01X134843Y529657D02*
X134131D01*
G01X165716Y500483D02*
X130126Y536073D01*
G01X136302Y528198D02*
X134843Y529657D01*
G01X165716Y500483D02*
X130126Y536073D01*
G01X138473Y526027D02*
X137762D01*
G01X165716Y500483D02*
X130126Y536073D01*
G01X139933Y524567D02*
X138473Y526027D01*
G01X165716Y500483D02*
X130126Y536073D01*
G01X142103Y522397D02*
X141392D01*
G01X165716Y500483D02*
X130126Y536073D01*
G01X149174Y515326D02*
X142103Y522397D01*
G01X165716Y500483D02*
X130126Y536073D01*
G01X151345Y513155D02*
X150634D01*
G01X165716Y500483D02*
X130126Y536073D01*
G01X152805Y511695D02*
X151345Y513155D01*
G01X165716Y500483D02*
X130126Y536073D01*
G01X154976Y509524D02*
X154264D01*
G01X165716Y500483D02*
X130126Y536073D01*
G01X165218Y499282D02*
X154976Y509524D01*
G01X165716Y500483D02*
X130126Y536073D01*
G01X325718Y499282D02*
X165218D01*
G01X326216Y500483D02*
X165716D01*
G01X112500Y528500D02*
Y565500D01*
G01X153000Y488000D02*
X112500Y528500D01*
G01X116389Y522912D02*
X114929Y524372D01*
G01X152502Y486799D02*
X118560Y520741D01*
G01X319000Y488000D02*
X153000D01*
G01X318502Y486799D02*
X152502D01*
G01X130126Y536073D02*
X125000D01*
G01X129628Y534872D02*
X124999D01*
G01X165716Y500483D02*
X130126Y536073D01*
G01X132672Y531828D02*
X129628Y534872D01*
G01X134843Y529657D02*
X134131D01*
G01X136302Y528198D02*
X134843Y529657D01*
G01X138473Y526027D02*
X137762D01*
G01X139933Y524567D02*
X138473Y526027D01*
G01X142103Y522397D02*
X141392D01*
G01X149174Y515326D02*
X142103Y522397D01*
G01X151345Y513155D02*
X150634D01*
G01X152805Y511695D02*
X151345Y513155D01*
G01X154976Y509524D02*
X154264D01*
G01X165218Y499282D02*
X154976Y509524D01*
G01X326216Y500483D02*
X165716D01*
G01X325718Y499282D02*
X165218D01*
G01X129628Y534872D02*
X124999D01*
G01X130126Y536073D02*
X125000D01*
G01X132672Y531828D02*
X129628Y534872D01*
G01X165716Y500483D02*
X130126Y536073D01*
G01X134843Y529657D02*
X134131D01*
G01X165716Y500483D02*
X130126Y536073D01*
G01X136302Y528198D02*
X134843Y529657D01*
G01X165716Y500483D02*
X130126Y536073D01*
G01X138473Y526027D02*
X137762D01*
G01X165716Y500483D02*
X130126Y536073D01*
G01X139933Y524567D02*
X138473Y526027D01*
G01X165716Y500483D02*
X130126Y536073D01*
G01X142103Y522397D02*
X141392D01*
G01X165716Y500483D02*
X130126Y536073D01*
G01X149174Y515326D02*
X142103Y522397D01*
G01X165716Y500483D02*
X130126Y536073D01*
G01X151345Y513155D02*
X150634D01*
G01X165716Y500483D02*
X130126Y536073D01*
G01X152805Y511695D02*
X151345Y513155D01*
G01X165716Y500483D02*
X130126Y536073D01*
G01X154976Y509524D02*
X154264D01*
G01X165716Y500483D02*
X130126Y536073D01*
G01X165218Y499282D02*
X154976Y509524D01*
G01X165716Y500483D02*
X130126Y536073D01*
G01X325718Y499282D02*
X165218D01*
G01X326216Y500483D02*
X165716D01*
G01X112500Y528500D02*
Y565500D01*
G01Y528500D02*
Y565500D01*
G01Y528500D02*
Y565500D01*
G01Y528500D02*
Y565500D01*
G01X153000Y488000D02*
X112500Y528500D01*
G01X116389Y522912D02*
X114929Y524372D01*
G01X153000Y488000D02*
X112500Y528500D01*
G01X152502Y486799D02*
X118560Y520741D01*
G01X153000Y488000D02*
X112500Y528500D01*
G01X318502Y486799D02*
X152502D01*
G01X319000Y488000D02*
X153000D01*
G01X149000Y622609D02*
X140094D01*
G01X149000Y621408D02*
X140095D01*
G01X149000D02*
X140095D01*
G01X149000Y622609D02*
X140094D01*
G01X141958Y611958D02*
X149042D01*
G01X141460Y613159D02*
X149000D01*
G01X140000Y610000D02*
X141958Y611958D01*
G01X138799Y610498D02*
X141460Y613159D01*
G01X140000Y607000D02*
Y610000D01*
G01X138799Y606502D02*
Y610498D01*
G01X142000Y605000D02*
X140000Y607000D01*
G01X141502Y603799D02*
X138799Y606502D01*
G01X191000Y605000D02*
X142000D01*
G01X190502Y603799D02*
X141502D01*
G01X141460Y613159D02*
X149000D01*
G01X141958Y611958D02*
X149042D01*
G01X138799Y610498D02*
X141460Y613159D01*
G01X140000Y610000D02*
X141958Y611958D01*
G01X138799Y606502D02*
Y610498D01*
G01X140000Y607000D02*
Y610000D01*
G01X141502Y603799D02*
X138799Y606502D01*
G01X142000Y605000D02*
X140000Y607000D01*
G01X190502Y603799D02*
X141502D01*
G01X191000Y605000D02*
X142000D01*
G01X149000Y622609D02*
X140094D01*
G01X149000Y621408D02*
X140095D01*
G01X149000D02*
X140095D01*
G01X149000Y622609D02*
X140094D01*
G01X177799Y644014D02*
Y641905D01*
G01X179000Y644512D02*
Y641906D01*
G01X176783Y645030D02*
X177799Y644014D01*
G01X177281Y646231D02*
X179000Y644512D01*
G01X171975Y645030D02*
X176783D01*
G01X172000Y646231D02*
X177281D01*
G01X179000Y644512D02*
Y641906D01*
G01X177799Y644014D02*
Y641905D01*
G01X177281Y646231D02*
X179000Y644512D01*
G01X176783Y645030D02*
X177799Y644014D01*
G01X172000Y646231D02*
X177281D01*
G01X171975Y645030D02*
X176783D01*
G01X149026Y691900D02*
X140094D01*
G01X149000Y690699D02*
X140095D01*
G01X149000D02*
X140095D01*
G01X149026Y691900D02*
X140094D01*
G01X149026Y673002D02*
X140095D01*
G01X149000Y671801D02*
X140094D01*
G01X149000D02*
X140094D01*
G01X149026Y673002D02*
X140095D01*
G01X149026Y701349D02*
X146194D01*
G01X149025Y700148D02*
X146195D01*
G01X149025D02*
X146195D01*
G01X149026Y701349D02*
X146194D01*
G01X149026Y682451D02*
X146194D01*
G01X149000Y681250D02*
X146195D01*
G01X149000D02*
X146195D01*
G01X149026Y682451D02*
X146194D01*
G01X149000Y632057D02*
X146195D01*
G01X149000Y630856D02*
X146194D01*
G01X177799Y644014D02*
Y641905D01*
G01X179000Y644512D02*
Y641906D01*
G01X176783Y645030D02*
X177799Y644014D01*
G01X177281Y646231D02*
X179000Y644512D01*
G01X171975Y645030D02*
X176783D01*
G01X172000Y646231D02*
X177281D01*
G01X179000Y644512D02*
Y641906D01*
G01X177799Y644014D02*
Y641905D01*
G01X177281Y646231D02*
X179000Y644512D01*
G01X176783Y645030D02*
X177799Y644014D01*
G01X172000Y646231D02*
X177281D01*
G01X171975Y645030D02*
X176783D01*
G01X149000Y630856D02*
X146194D01*
G01X149000Y632057D02*
X146195D01*
G01X149026Y691900D02*
X140094D01*
G01X149000Y690699D02*
X140095D01*
G01X149000D02*
X140095D01*
G01X149026Y691900D02*
X140094D01*
G01X149026Y673002D02*
X140095D01*
G01X149000Y671801D02*
X140094D01*
G01X149000D02*
X140094D01*
G01X149026Y673002D02*
X140095D01*
G01X149026Y710798D02*
X140094D01*
G01X149025Y709597D02*
X140095D01*
G01X149025D02*
X140095D01*
G01X149026Y710798D02*
X140094D01*
G01X149000Y720246D02*
X146195D01*
G01X149026Y719045D02*
X146194D01*
G01X149026D02*
X146194D01*
G01X149000Y720246D02*
X146195D01*
G01X149026Y710798D02*
X140094D01*
G01X149025Y709597D02*
X140095D01*
G01X149025D02*
X140095D01*
G01X149026Y710798D02*
X140094D01*
G01X190130Y828630D02*
X159101Y797601D01*
G01X190628Y827429D02*
X159599Y796400D01*
G01X190628Y827429D02*
X159599Y796400D01*
G01X190130Y828630D02*
X159101Y797601D01*
G01X190130Y828630D02*
X159101Y797601D01*
G01X190628Y827429D02*
X159599Y796400D01*
G01X190130Y828630D02*
X159101Y797601D01*
G01X190628Y827429D02*
X159599Y796400D01*
G01X190628Y827429D02*
X159599Y796400D01*
G01X190130Y828630D02*
X159101Y797601D01*
G01X190628Y827429D02*
X159599Y796400D01*
G01X190130Y828630D02*
X159101Y797601D01*
G01X190130Y828630D02*
X159101Y797601D01*
G01X190628Y827429D02*
X159599Y796400D01*
G01X190628Y827429D02*
X159599Y796400D01*
G01X190130Y828630D02*
X159101Y797601D01*
G01X161502Y920299D02*
X137228Y944573D01*
G01X315362Y920299D02*
X161502D01*
G01D02*
X137228Y944573D01*
G01X315362Y920299D02*
X161502D01*
G01X180799Y935701D02*
X321299D01*
G01X180301Y934500D02*
X320801D01*
G01X174992Y941508D02*
X180799Y935701D01*
G01X174494Y940307D02*
X180301Y934500D01*
G01X168001Y941508D02*
X174992D01*
G01X167998Y940307D02*
X174494D01*
G01X180301Y934500D02*
X320801D01*
G01X180799Y935701D02*
X321299D01*
G01X174494Y940307D02*
X180301Y934500D01*
G01X174992Y941508D02*
X180799Y935701D01*
G01X167998Y940307D02*
X174494D01*
G01X168001Y941508D02*
X174992D01*
G01X180799Y935701D02*
X321299D01*
G01X180301Y934500D02*
X320801D01*
G01X174992Y941508D02*
X180799Y935701D01*
G01X174494Y940307D02*
X180301Y934500D01*
G01X168001Y941508D02*
X174992D01*
G01X167998Y940307D02*
X174494D01*
G01X180301Y934500D02*
X320801D01*
G01X180799Y935701D02*
X321299D01*
G01X174494Y940307D02*
X180301Y934500D01*
G01X174992Y941508D02*
X180799Y935701D01*
G01X167998Y940307D02*
X174494D01*
G01X168001Y941508D02*
X174992D01*
G01X117096Y964705D02*
X116384D01*
G01X118555Y963246D02*
X117096Y964705D01*
G01X120726Y961075D02*
X120015D01*
G01X122185Y959616D02*
X120726Y961075D01*
G01X124356Y957445D02*
X123645D01*
G01X131427Y950374D02*
X124356Y957445D01*
G01X133598Y948203D02*
X132887D01*
G01X135058Y946743D02*
X133598Y948203D01*
G01X137228Y944573D02*
X136517D01*
G01X315860Y921500D02*
X162000D01*
G01X117096Y964705D02*
X116384D01*
G01X118555Y963246D02*
X117096Y964705D01*
G01X120726Y961075D02*
X120015D01*
G01X122185Y959616D02*
X120726Y961075D01*
G01X124356Y957445D02*
X123645D01*
G01X131427Y950374D02*
X124356Y957445D01*
G01X133598Y948203D02*
X132887D01*
G01X135058Y946743D02*
X133598Y948203D01*
G01X137228Y944573D02*
X136517D01*
G01X315860Y921500D02*
X162000D01*
G01X177799Y1049526D02*
Y1047417D01*
G01X179000Y1050024D02*
Y1047418D01*
G01X176783Y1050542D02*
X177799Y1049526D01*
G01X177281Y1051743D02*
X179000Y1050024D01*
G01X171975Y1050542D02*
X176783D01*
G01X171974Y1051743D02*
X177281D01*
G01X179000Y1050024D02*
Y1047418D01*
G01X177799Y1049526D02*
Y1047417D01*
G01X177281Y1051743D02*
X179000Y1050024D01*
G01X176783Y1050542D02*
X177799Y1049526D01*
G01X171974Y1051743D02*
X177281D01*
G01X171975Y1050542D02*
X176783D01*
G01X149000Y1028121D02*
X140094D01*
G01X149000Y1026920D02*
X140095D01*
G01X149000D02*
X140095D01*
G01X149000Y1028121D02*
X140094D01*
G01X149000Y1037569D02*
X146195D01*
G01X149132Y1036368D02*
X146194D01*
G01X149132D02*
X146194D01*
G01X149000Y1037569D02*
X146195D01*
G01X177799Y1049526D02*
Y1047417D01*
G01X179000Y1050024D02*
Y1047418D01*
G01X176783Y1050542D02*
X177799Y1049526D01*
G01X177281Y1051743D02*
X179000Y1050024D01*
G01X171975Y1050542D02*
X176783D01*
G01X171974Y1051743D02*
X177281D01*
G01X179000Y1050024D02*
Y1047418D01*
G01X177799Y1049526D02*
Y1047417D01*
G01X177281Y1051743D02*
X179000Y1050024D01*
G01X176783Y1050542D02*
X177799Y1049526D01*
G01X171974Y1051743D02*
X177281D01*
G01X171975Y1050542D02*
X176783D01*
G01X145970Y1017470D02*
X149000D01*
G01X145472Y1018671D02*
X149000D01*
G01X144000Y1015500D02*
X145970Y1017470D01*
G01X142799Y1015998D02*
X145472Y1018671D01*
G01X144000Y1012000D02*
Y1015500D01*
G01X142799Y1011502D02*
Y1015998D01*
G01X146000Y1010000D02*
X144000Y1012000D01*
G01X145502Y1008799D02*
X142799Y1011502D01*
G01X186300Y1010000D02*
X146000D01*
G01X185802Y1008799D02*
X145502D01*
G01X145472Y1018671D02*
X149000D01*
G01X145970Y1017470D02*
X149000D01*
G01X142799Y1015998D02*
X145472Y1018671D01*
G01X144000Y1015500D02*
X145970Y1017470D01*
G01X142799Y1011502D02*
Y1015998D01*
G01X144000Y1012000D02*
Y1015500D01*
G01X145502Y1008799D02*
X142799Y1011502D01*
G01X146000Y1010000D02*
X144000Y1012000D01*
G01X185802Y1008799D02*
X145502D01*
G01X186300Y1010000D02*
X146000D01*
G01X149000Y1028121D02*
X140094D01*
G01X149000Y1026920D02*
X140095D01*
G01X149000D02*
X140095D01*
G01X149000Y1028121D02*
X140094D01*
G01X149026Y1116310D02*
X140094D01*
G01X149025Y1115109D02*
X140095D01*
G01X149025D02*
X140095D01*
G01X149026Y1116310D02*
X140094D01*
G01X149026Y1097412D02*
X140094D01*
G01X149000Y1096211D02*
X140095D01*
G01X149000D02*
X140095D01*
G01X149026Y1097412D02*
X140094D01*
G01X149026Y1078514D02*
X140095D01*
G01X149000Y1077313D02*
X140094D01*
G01X149000D02*
X140094D01*
G01X149026Y1078514D02*
X140095D01*
G01X149026Y1125758D02*
X146195D01*
G01X149026Y1124557D02*
X146194D01*
G01X149026D02*
X146194D01*
G01X149026Y1125758D02*
X146195D01*
G01X149026Y1106861D02*
X146194D01*
G01X149025Y1105660D02*
X146195D01*
G01X149025D02*
X146195D01*
G01X149026Y1106861D02*
X146194D01*
G01X149026Y1087963D02*
X146194D01*
G01X149000Y1086762D02*
X146195D01*
G01X149000D02*
X146195D01*
G01X149026Y1087963D02*
X146194D01*
G01X149026Y1116310D02*
X140094D01*
G01X149025Y1115109D02*
X140095D01*
G01X149025D02*
X140095D01*
G01X149026Y1116310D02*
X140094D01*
G01X149026Y1097412D02*
X140094D01*
G01X149000Y1096211D02*
X140095D01*
G01X149000D02*
X140095D01*
G01X149026Y1097412D02*
X140094D01*
G01X149026Y1078514D02*
X140095D01*
G01X149000Y1077313D02*
X140094D01*
G01X149000D02*
X140094D01*
G01X149026Y1078514D02*
X140095D01*
G01X139480Y1347020D02*
X130501D01*
G01X138982Y1345819D02*
X130498D01*
G01X153594Y1332906D02*
X139480Y1347020D01*
G01X153096Y1331705D02*
X138982Y1345819D01*
G01X295293Y1332906D02*
X153594D01*
G01X159657Y1331705D02*
X153096D01*
G01X164791D02*
X162727D01*
G01X169925D02*
X167861D01*
G01X185500D02*
X172995D01*
G01X138982Y1345819D02*
X130498D01*
G01X139480Y1347020D02*
X130501D01*
G01X153096Y1331705D02*
X138982Y1345819D01*
G01X153594Y1332906D02*
X139480Y1347020D01*
G01X159657Y1331705D02*
X153096D01*
G01X295293Y1332906D02*
X153594D01*
G01X164791Y1331705D02*
X162727D01*
G01X295293Y1332906D02*
X153594D01*
G01X169925Y1331705D02*
X167861D01*
G01X295293Y1332906D02*
X153594D01*
G01X185500Y1331705D02*
X172995D01*
G01X295293Y1332906D02*
X153594D01*
G01X295293D02*
X153594D01*
G01X295293D02*
X153594D01*
G01X113701Y1336498D02*
Y1374998D01*
G01X112500Y1354507D02*
Y1356571D01*
G01Y1336000D02*
Y1351437D01*
G01X121340Y1328860D02*
X113701Y1336498D01*
G01X113959Y1334541D02*
X112500Y1336000D01*
G01X116130Y1332370D02*
X115419D01*
G01X117590Y1330910D02*
X116130Y1332370D01*
G01X119761Y1328739D02*
X119049D01*
G01X130700Y1319500D02*
X121340Y1328860D01*
G01X126500Y1322000D02*
X119761Y1328739D01*
G01X130202Y1318299D02*
X126500Y1322000D01*
G01X289000Y1319500D02*
X130700D01*
G01X288502Y1318299D02*
X130202D01*
G01X113701Y1336498D02*
Y1374998D01*
G01Y1336498D02*
Y1374998D01*
G01X112500Y1354507D02*
Y1356571D01*
G01X113701Y1336498D02*
Y1374998D01*
G01X112500Y1336000D02*
Y1351437D01*
G01X113701Y1336498D02*
Y1374998D01*
G01X113959Y1334541D02*
X112500Y1336000D01*
G01X121340Y1328860D02*
X113701Y1336498D01*
G01X116130Y1332370D02*
X115419D01*
G01X121340Y1328860D02*
X113701Y1336498D01*
G01X117590Y1330910D02*
X116130Y1332370D01*
G01X121340Y1328860D02*
X113701Y1336498D01*
G01X119761Y1328739D02*
X119049D01*
G01X121340Y1328860D02*
X113701Y1336498D01*
G01X126500Y1322000D02*
X119761Y1328739D01*
G01X130700Y1319500D02*
X121340Y1328860D01*
G01X130202Y1318299D02*
X126500Y1322000D01*
G01X130700Y1319500D02*
X121340Y1328860D01*
G01X288502Y1318299D02*
X130202D01*
G01X289000Y1319500D02*
X130700D01*
G01X139480Y1347020D02*
X130501D01*
G01X138982Y1345819D02*
X130498D01*
G01X153594Y1332906D02*
X139480Y1347020D01*
G01X153096Y1331705D02*
X138982Y1345819D01*
G01X295293Y1332906D02*
X153594D01*
G01X159657Y1331705D02*
X153096D01*
G01X164791D02*
X162727D01*
G01X169925D02*
X167861D01*
G01X185500D02*
X172995D01*
G01X138982Y1345819D02*
X130498D01*
G01X139480Y1347020D02*
X130501D01*
G01X153096Y1331705D02*
X138982Y1345819D01*
G01X153594Y1332906D02*
X139480Y1347020D01*
G01X159657Y1331705D02*
X153096D01*
G01X295293Y1332906D02*
X153594D01*
G01X164791Y1331705D02*
X162727D01*
G01X295293Y1332906D02*
X153594D01*
G01X169925Y1331705D02*
X167861D01*
G01X295293Y1332906D02*
X153594D01*
G01X185500Y1331705D02*
X172995D01*
G01X295293Y1332906D02*
X153594D01*
G01X295293D02*
X153594D01*
G01X295293D02*
X153594D01*
G01X145482Y1422982D02*
X149026D01*
G01X144984Y1424183D02*
X149000D01*
G01X144000Y1421500D02*
X145482Y1422982D01*
G01X142799Y1421998D02*
X144984Y1424183D01*
G01X144000Y1417000D02*
Y1421500D01*
G01X142799Y1416502D02*
Y1421998D01*
G01X145500Y1415500D02*
X144000Y1417000D01*
G01X145002Y1414299D02*
X142799Y1416502D01*
G01X188797Y1415500D02*
X145500D01*
G01X188299Y1414299D02*
X145002D01*
G01X144984Y1424183D02*
X149000D01*
G01X145482Y1422982D02*
X149026D01*
G01X142799Y1421998D02*
X144984Y1424183D01*
G01X144000Y1421500D02*
X145482Y1422982D01*
G01X142799Y1416502D02*
Y1421998D01*
G01X144000Y1417000D02*
Y1421500D01*
G01X145002Y1414299D02*
X142799Y1416502D01*
G01X145500Y1415500D02*
X144000Y1417000D01*
G01X188299Y1414299D02*
X145002D01*
G01X188797Y1415500D02*
X145500D01*
G01X112500Y1364775D02*
Y1374500D01*
G01Y1359641D02*
Y1361705D01*
G01Y1364775D02*
Y1374500D01*
G01Y1359641D02*
Y1361705D01*
G01X177799Y1455038D02*
Y1452929D01*
G01X179000Y1455536D02*
Y1452930D01*
G01X176783Y1456054D02*
X177799Y1455038D01*
G01X177281Y1457255D02*
X179000Y1455536D01*
G01X171975Y1456054D02*
X176783D01*
G01X172000Y1457255D02*
X177281D01*
G01X179000Y1455536D02*
Y1452930D01*
G01X177799Y1455038D02*
Y1452929D01*
G01X177281Y1457255D02*
X179000Y1455536D01*
G01X176783Y1456054D02*
X177799Y1455038D01*
G01X172000Y1457255D02*
X177281D01*
G01X171975Y1456054D02*
X176783D01*
G01X149025Y1501723D02*
X140095D01*
G01X149025D02*
X140095D01*
G01X149000Y1484026D02*
X140095D01*
G01X149026Y1482825D02*
X140094D01*
G01X149026D02*
X140094D01*
G01X149000Y1484026D02*
X140095D01*
G01X149000Y1433633D02*
X140094D01*
G01X149000Y1432432D02*
X140095D01*
G01X149000D02*
X140095D01*
G01X149000Y1433633D02*
X140094D01*
G01X149026Y1493475D02*
X146194D01*
G01X149025Y1492274D02*
X146195D01*
G01X149025D02*
X146195D01*
G01X149026Y1493475D02*
X146194D01*
G01X149081Y1443081D02*
X146195D01*
G01X149000Y1441880D02*
X146194D01*
G01X149000D02*
X146194D01*
G01X149081Y1443081D02*
X146195D01*
G01X177799Y1455038D02*
Y1452929D01*
G01X179000Y1455536D02*
Y1452930D01*
G01X176783Y1456054D02*
X177799Y1455038D01*
G01X177281Y1457255D02*
X179000Y1455536D01*
G01X171975Y1456054D02*
X176783D01*
G01X172000Y1457255D02*
X177281D01*
G01X179000Y1455536D02*
Y1452930D01*
G01X177799Y1455038D02*
Y1452929D01*
G01X177281Y1457255D02*
X179000Y1455536D01*
G01X176783Y1456054D02*
X177799Y1455038D01*
G01X172000Y1457255D02*
X177281D01*
G01X171975Y1456054D02*
X176783D01*
G01X149025Y1501723D02*
X140095D01*
G01X149025D02*
X140095D01*
G01X149000Y1484026D02*
X140095D01*
G01X149026Y1482825D02*
X140094D01*
G01X149026D02*
X140094D01*
G01X149000Y1484026D02*
X140095D01*
G01X149000Y1433633D02*
X140094D01*
G01X149000Y1432432D02*
X140095D01*
G01X149000D02*
X140095D01*
G01X149000Y1433633D02*
X140094D01*
G01X149026Y1521822D02*
X140094D01*
G01X149025Y1520621D02*
X140095D01*
G01X149025D02*
X140095D01*
G01X149026Y1521822D02*
X140094D01*
G01X149026Y1502924D02*
X140094D01*
G01X149026Y1531270D02*
X146195D01*
G01X149026Y1530069D02*
X146194D01*
G01X149026D02*
X146194D01*
G01X149026Y1531270D02*
X146195D01*
G01X149026Y1512373D02*
X146194D01*
G01X149025Y1511172D02*
X146195D01*
G01X149025D02*
X146195D01*
G01X149026Y1512373D02*
X146194D01*
G01X149026Y1502924D02*
X140094D01*
G01X149026Y1521822D02*
X140094D01*
G01X149025Y1520621D02*
X140095D01*
G01X149025D02*
X140095D01*
G01X149026Y1521822D02*
X140094D01*
G01X149026Y1502924D02*
X140094D01*
G01X149026D02*
X140094D01*
G01X205201Y1626299D02*
X112000Y1719500D01*
G01X205201Y1626299D02*
X112000Y1719500D01*
G01X126638Y1773138D02*
X201347Y1698429D01*
G01X127839Y1773636D02*
X201845Y1699630D01*
G01X126638Y1773138D02*
X201347Y1698429D01*
G01X127839Y1773636D02*
X201845Y1699630D01*
G01X126638Y1773138D02*
X201347Y1698429D01*
G01X127839Y1773636D02*
X201845Y1699630D01*
G01X126638Y1773138D02*
X201347Y1698429D01*
G01X127839Y1773636D02*
X201845Y1699630D01*
G01X127839Y1773636D02*
X201845Y1699630D01*
G01X126638Y1773138D02*
X201347Y1698429D01*
G01X127839Y1773636D02*
X201845Y1699630D01*
G01X126638Y1773138D02*
X201347Y1698429D01*
G01X127839Y1773636D02*
X201845Y1699630D01*
G01X126638Y1773138D02*
X201347Y1698429D01*
G01X127839Y1773636D02*
X201845Y1699630D01*
G01X126638Y1773138D02*
X201347Y1698429D01*
G01X130799Y1717757D02*
Y1748502D01*
G01Y1717757D02*
Y1748502D01*
G01Y1717757D02*
Y1748502D01*
G01X132000Y1718255D02*
Y1733598D01*
G01X130799Y1717757D02*
Y1748502D01*
G01X134158Y1716098D02*
X132000Y1718255D01*
G01X206906Y1641650D02*
X130799Y1717757D01*
G01X135617Y1714639D02*
X134158Y1716098D01*
G01X206906Y1641650D02*
X130799Y1717757D01*
G01X136329Y1714639D02*
X135617D01*
G01X206906Y1641650D02*
X130799Y1717757D01*
G01X139248Y1711008D02*
X137788Y1712468D01*
G01X206906Y1641650D02*
X130799Y1717757D01*
G01X139959Y1711008D02*
X139248D01*
G01X206906Y1641650D02*
X130799Y1717757D01*
G01X207756Y1642500D02*
X141419Y1708837D01*
G01X206906Y1641650D02*
X130799Y1717757D01*
G01D02*
Y1748502D01*
G01X132000Y1718255D02*
Y1733598D01*
G01X206906Y1641650D02*
X130799Y1717757D01*
G01X134158Y1716098D02*
X132000Y1718255D01*
G01X135617Y1714639D02*
X134158Y1716098D01*
G01X136329Y1714639D02*
X135617D01*
G01X139248Y1711008D02*
X137788Y1712468D01*
G01X139959Y1711008D02*
X139248D01*
G01X207756Y1642500D02*
X141419Y1708837D01*
G01X207756Y1642500D02*
X141419Y1708837D01*
G01X130799Y1717757D02*
Y1748502D01*
G01Y1717757D02*
Y1748502D01*
G01Y1717757D02*
Y1748502D01*
G01X132000Y1718255D02*
Y1733598D01*
G01X130799Y1717757D02*
Y1748502D01*
G01X134158Y1716098D02*
X132000Y1718255D01*
G01X206906Y1641650D02*
X130799Y1717757D01*
G01X135617Y1714639D02*
X134158Y1716098D01*
G01X206906Y1641650D02*
X130799Y1717757D01*
G01X136329Y1714639D02*
X135617D01*
G01X206906Y1641650D02*
X130799Y1717757D01*
G01X139248Y1711008D02*
X137788Y1712468D01*
G01X206906Y1641650D02*
X130799Y1717757D01*
G01X139959Y1711008D02*
X139248D01*
G01X206906Y1641650D02*
X130799Y1717757D01*
G01X207756Y1642500D02*
X141419Y1708837D01*
G01X206906Y1641650D02*
X130799Y1717757D01*
G01D02*
Y1748502D01*
G01X132000Y1718255D02*
Y1733598D01*
G01X206906Y1641650D02*
X130799Y1717757D01*
G01X134158Y1716098D02*
X132000Y1718255D01*
G01X135617Y1714639D02*
X134158Y1716098D01*
G01X136329Y1714639D02*
X135617D01*
G01X139248Y1711008D02*
X137788Y1712468D01*
G01X139959Y1711008D02*
X139248D01*
G01X207756Y1642500D02*
X141419Y1708837D01*
G01X207756Y1642500D02*
X141419Y1708837D01*
G01X112000Y1719500D02*
Y1782000D01*
G01Y1719500D02*
Y1782000D01*
G01Y1719500D02*
Y1782000D01*
G01Y1719500D02*
Y1782000D01*
G01Y1719500D02*
Y1782000D01*
G01X113201Y1719998D02*
Y1748892D01*
G01X112000Y1719500D02*
Y1782000D01*
G01X205699Y1627500D02*
X113201Y1719998D01*
G01X112000Y1719500D02*
Y1782000D01*
G01X113201Y1719998D02*
Y1748892D01*
G01X205699Y1627500D02*
X113201Y1719998D01*
G01X126638Y1773138D02*
X201347Y1698429D01*
G01X127839Y1773636D02*
X201845Y1699630D01*
G01X127839Y1773636D02*
X201845Y1699630D01*
G01X126638Y1773138D02*
X201347Y1698429D01*
G01X126638Y1787412D02*
Y1773138D01*
G01X127839Y1787910D02*
Y1773636D01*
G01X126638Y1787412D02*
Y1773138D01*
G01X127839Y1787910D02*
Y1773636D01*
G01X126638Y1787412D02*
Y1773138D01*
G01X127839Y1787910D02*
Y1773636D01*
G01X126638Y1787412D02*
Y1773138D01*
G01X127839Y1787910D02*
Y1773636D01*
G01Y1787910D02*
Y1773636D01*
G01X126638Y1787412D02*
Y1773138D01*
G01X127839Y1787910D02*
Y1773636D01*
G01X126638Y1787412D02*
Y1773138D01*
G01X127839Y1787910D02*
Y1773636D01*
G01X126638Y1787412D02*
Y1773138D01*
G01X127839Y1787910D02*
Y1773636D01*
G01X126638Y1787412D02*
Y1773138D01*
G01X128468Y1752532D02*
X126002D01*
G01X127970Y1751331D02*
X125997D01*
G01X132000Y1749000D02*
X128468Y1752532D01*
G01X130799Y1748502D02*
X127970Y1751331D01*
G01X132000Y1746936D02*
Y1749000D01*
G01Y1741802D02*
Y1743866D01*
G01Y1736668D02*
Y1738732D01*
G01X127970Y1751331D02*
X125997D01*
G01X128468Y1752532D02*
X126002D01*
G01X130799Y1748502D02*
X127970Y1751331D01*
G01X132000Y1749000D02*
X128468Y1752532D01*
G01X132000Y1746936D02*
Y1749000D01*
G01Y1741802D02*
Y1743866D01*
G01Y1736668D02*
Y1738732D01*
G01X128468Y1752532D02*
X126002D01*
G01X127970Y1751331D02*
X125997D01*
G01X132000Y1749000D02*
X128468Y1752532D01*
G01X130799Y1748502D02*
X127970Y1751331D01*
G01X132000Y1746936D02*
Y1749000D01*
G01Y1741802D02*
Y1743866D01*
G01Y1736668D02*
Y1738732D01*
G01X127970Y1751331D02*
X125997D01*
G01X128468Y1752532D02*
X126002D01*
G01X130799Y1748502D02*
X127970Y1751331D01*
G01X132000Y1749000D02*
X128468Y1752532D01*
G01X132000Y1746936D02*
Y1749000D01*
G01Y1741802D02*
Y1743866D01*
G01Y1736668D02*
Y1738732D01*
G01X113201Y1780434D02*
Y1782498D01*
G01Y1775300D02*
Y1777364D01*
G01Y1770166D02*
Y1772230D01*
G01Y1757096D02*
Y1767096D01*
G01Y1751962D02*
Y1754026D01*
G01Y1780434D02*
Y1782498D01*
G01Y1775300D02*
Y1777364D01*
G01Y1770166D02*
Y1772230D01*
G01Y1757096D02*
Y1767096D01*
G01Y1751962D02*
Y1754026D01*
G01X126638Y1787412D02*
Y1773138D01*
G01X127839Y1787910D02*
Y1773636D01*
G01Y1787910D02*
Y1773636D01*
G01X126638Y1787412D02*
Y1773138D01*
G01X177799Y1860550D02*
Y1858441D01*
G01X179000Y1861048D02*
Y1858442D01*
G01X176783Y1861566D02*
X177799Y1860550D01*
G01X177281Y1862767D02*
X179000Y1861048D01*
G01X172475Y1861566D02*
X176783D01*
G01X172500Y1862767D02*
X177281D01*
G01X179000Y1861048D02*
Y1858442D01*
G01X177799Y1860550D02*
Y1858441D01*
G01X177281Y1862767D02*
X179000Y1861048D01*
G01X176783Y1861566D02*
X177799Y1860550D01*
G01X172500Y1862767D02*
X177281D01*
G01X172475Y1861566D02*
X176783D01*
G01X148550Y1837894D02*
X140045D01*
G01X148450Y1839095D02*
X140144D01*
G01X148450D02*
X140144D01*
G01X148550Y1837894D02*
X140045D01*
G01X148500Y1847392D02*
X146194D01*
G01X148526Y1848593D02*
X146195D01*
G01X148526D02*
X146195D01*
G01X148500Y1847392D02*
X146194D01*
G01X177799Y1860550D02*
Y1858441D01*
G01X179000Y1861048D02*
Y1858442D01*
G01X176783Y1861566D02*
X177799Y1860550D01*
G01X177281Y1862767D02*
X179000Y1861048D01*
G01X172475Y1861566D02*
X176783D01*
G01X172500Y1862767D02*
X177281D01*
G01X179000Y1861048D02*
Y1858442D01*
G01X177799Y1860550D02*
Y1858441D01*
G01X177281Y1862767D02*
X179000Y1861048D01*
G01X176783Y1861566D02*
X177799Y1860550D01*
G01X172500Y1862767D02*
X177281D01*
G01X172475Y1861566D02*
X176783D01*
G01X146494Y1828494D02*
X148506D01*
G01X148525Y1829695D02*
X145996D01*
G01X145000Y1827000D02*
X146494Y1828494D01*
G01X145996Y1829695D02*
X143799Y1827498D01*
G01X145000Y1823500D02*
Y1827000D01*
G01X143799Y1827498D02*
Y1823002D01*
G01X147500Y1821000D02*
X145000Y1823500D01*
G01X143799Y1823002D02*
X147002Y1819799D01*
G01X172878Y1821000D02*
X147500D01*
G01X147002Y1819799D02*
X303002D01*
G01X178012Y1821000D02*
X175948D01*
G01X147002Y1819799D02*
X303002D01*
G01X183146Y1821000D02*
X181082D01*
G01X147002Y1819799D02*
X303002D01*
G01X147002D02*
X303002D01*
G01X147002D02*
X303002D01*
G01X147002D02*
X303002D01*
G01X147002D02*
X303002D01*
G01X172878Y1821000D02*
X147500D01*
G01X178012D02*
X175948D01*
G01X183146D02*
X181082D01*
G01X143799Y1823002D02*
X147002Y1819799D01*
G01X147500Y1821000D02*
X145000Y1823500D01*
G01X143799Y1827498D02*
Y1823002D01*
G01X145000Y1823500D02*
Y1827000D01*
G01X145996Y1829695D02*
X143799Y1827498D01*
G01X145000Y1827000D02*
X146494Y1828494D01*
G01X148525Y1829695D02*
X145996D01*
G01X146494Y1828494D02*
X148506D01*
G01X148450Y1839095D02*
X140144D01*
G01X148550Y1837894D02*
X140045D01*
G01X148550D02*
X140045D01*
G01X148450Y1839095D02*
X140144D01*
G01X148575Y1926083D02*
X140045D01*
G01X148450Y1927284D02*
X140144D01*
G01X148450D02*
X140144D01*
G01X148575Y1926083D02*
X140045D01*
G01X148050Y1907185D02*
X140045D01*
G01X147976Y1908386D02*
X140144D01*
G01X147976D02*
X140144D01*
G01X148050Y1907185D02*
X140045D01*
G01X148550Y1888287D02*
X140044D01*
G01X148450Y1889488D02*
X140145D01*
G01X148450D02*
X140145D01*
G01X148550Y1888287D02*
X140044D01*
G01X148526Y1935581D02*
X146194D01*
G01X148526Y1936782D02*
X146195D01*
G01X148526D02*
X146195D01*
G01X148526Y1935581D02*
X146194D01*
G01X148525Y1916684D02*
X146195D01*
G01X148526Y1917885D02*
X146194D01*
G01X148526D02*
X146194D01*
G01X148525Y1916684D02*
X146195D01*
G01X148525Y1897786D02*
X146195D01*
G01X148526Y1898987D02*
X146194D01*
G01X148526D02*
X146194D01*
G01X148525Y1897786D02*
X146195D01*
G01X148575Y1926083D02*
X140045D01*
G01X148450Y1927284D02*
X140144D01*
G01X148450D02*
X140144D01*
G01X148575Y1926083D02*
X140045D01*
G01X148050Y1907185D02*
X140045D01*
G01X147976Y1908386D02*
X140144D01*
G01X147976D02*
X140144D01*
G01X148050Y1907185D02*
X140045D01*
G01X148550Y1888287D02*
X140044D01*
G01X148450Y1889488D02*
X140145D01*
G01X148450D02*
X140145D01*
G01X148550Y1888287D02*
X140044D01*
G01X186766Y110901D02*
X184702D01*
G01X242702D02*
X189836D01*
G01X399000Y267199D02*
X242702Y110901D01*
G01X400201Y266701D02*
X243200Y109700D01*
G01X186766Y110901D02*
X184702D01*
G01X242702D02*
X189836D01*
G01X400201Y266701D02*
X243200Y109700D01*
G01X399000Y267199D02*
X242702Y110901D01*
G01X374299Y265799D02*
X239061Y130561D01*
G01X375500Y265301D02*
X239559Y129360D01*
G01X375500Y265301D02*
X239559Y129360D01*
G01X374299Y265799D02*
X239061Y130561D01*
G01X374299Y265799D02*
X239061Y130561D01*
G01X375500Y265301D02*
X239559Y129360D01*
G01X375500Y265301D02*
X239559Y129360D01*
G01X374299Y265799D02*
X239061Y130561D01*
G01X198919Y240701D02*
X191500D01*
G01X291199Y239500D02*
X191499D01*
G01X204053Y240701D02*
X201989D01*
G01X291199Y239500D02*
X191499D01*
G01X209187Y240701D02*
X207123D01*
G01X291199Y239500D02*
X191499D01*
G01X222257Y240701D02*
X212257D01*
G01X291199Y239500D02*
X191499D01*
G01X227391Y240701D02*
X225327D01*
G01X291199Y239500D02*
X191499D01*
G01X290701Y240701D02*
X230461D01*
G01X291199Y239500D02*
X191499D01*
G01X291199D02*
X191499D01*
G01X198919Y240701D02*
X191500D01*
G01X204053D02*
X201989D01*
G01X209187D02*
X207123D01*
G01X222257D02*
X212257D01*
G01X227391D02*
X225327D01*
G01X290701D02*
X230461D01*
G01X198919D02*
X191500D01*
G01X291199Y239500D02*
X191499D01*
G01X204053Y240701D02*
X201989D01*
G01X291199Y239500D02*
X191499D01*
G01X209187Y240701D02*
X207123D01*
G01X291199Y239500D02*
X191499D01*
G01X222257Y240701D02*
X212257D01*
G01X291199Y239500D02*
X191499D01*
G01X227391Y240701D02*
X225327D01*
G01X291199Y239500D02*
X191499D01*
G01X290701Y240701D02*
X230461D01*
G01X291199Y239500D02*
X191499D01*
G01X291199D02*
X191499D01*
G01X198919Y240701D02*
X191500D01*
G01X204053D02*
X201989D01*
G01X209187D02*
X207123D01*
G01X222257D02*
X212257D01*
G01X227391D02*
X225327D01*
G01X290701D02*
X230461D01*
G01X187921Y207921D02*
X186462Y206462D01*
G01X197163Y217163D02*
X190092Y210092D01*
G01X204952Y224952D02*
X199334Y219334D01*
G01X207016Y224952D02*
X204952D01*
G01X292337Y223751D02*
X205450D01*
G01X212150Y224952D02*
X210086D01*
G01X292337Y223751D02*
X205450D01*
G01X217284Y224952D02*
X215220D01*
G01X292337Y223751D02*
X205450D01*
G01X230354Y224952D02*
X220354D01*
G01X292337Y223751D02*
X205450D01*
G01X235488Y224952D02*
X233424D01*
G01X292337Y223751D02*
X205450D01*
G01X240622Y224952D02*
X238558D01*
G01X292337Y223751D02*
X205450D01*
G01X253099Y224952D02*
X243692D01*
G01X292337Y223751D02*
X205450D01*
G01X258233Y224952D02*
X256169D01*
G01X292337Y223751D02*
X205450D01*
G01X292337D02*
X205450D01*
G01X292337D02*
X205450D01*
G01X292337D02*
X205450D01*
G01X187921Y207921D02*
X186462Y206462D01*
G01X197163Y217163D02*
X190092Y210092D01*
G01X204952Y224952D02*
X199334Y219334D01*
G01X292337Y223751D02*
X205450D01*
G01X207016Y224952D02*
X204952D01*
G01X212150D02*
X210086D01*
G01X217284D02*
X215220D01*
G01X230354D02*
X220354D01*
G01X235488D02*
X233424D01*
G01X240622D02*
X238558D01*
G01X253099D02*
X243692D01*
G01X258233D02*
X256169D01*
G01X189500Y398000D02*
X303650D01*
G01X189500D02*
X303650D01*
G01X189500D02*
X303650D01*
G01X256251Y399201D02*
X258315D01*
G01X189500Y398000D02*
X303650D01*
G01X234562Y399201D02*
X253181D01*
G01X189500Y398000D02*
X303650D01*
G01X229428Y399201D02*
X231492D01*
G01X189500Y398000D02*
X303650D01*
G01X189002Y399201D02*
X226358D01*
G01X189500Y398000D02*
X303650D01*
G01X189500D02*
X303650D01*
G01X256251Y399201D02*
X258315D01*
G01X234562D02*
X253181D01*
G01X229428D02*
X231492D01*
G01X189002D02*
X226358D01*
G01X189500Y398000D02*
X303650D01*
G01X189500D02*
X303650D01*
G01X189500D02*
X303650D01*
G01X256251Y399201D02*
X258315D01*
G01X189500Y398000D02*
X303650D01*
G01X234562Y399201D02*
X253181D01*
G01X189500Y398000D02*
X303650D01*
G01X229428Y399201D02*
X231492D01*
G01X189500Y398000D02*
X303650D01*
G01X189002Y399201D02*
X226358D01*
G01X189500Y398000D02*
X303650D01*
G01X189500D02*
X303650D01*
G01X189500D02*
X303650D01*
G01X189500D02*
X303650D01*
G01X256251Y399201D02*
X258315D01*
G01X189500Y398000D02*
X303650D01*
G01X234562Y399201D02*
X253181D01*
G01X189500Y398000D02*
X303650D01*
G01X229428Y399201D02*
X231492D01*
G01X189500Y398000D02*
X303650D01*
G01X189002Y399201D02*
X226358D01*
G01X189500Y398000D02*
X303650D01*
G01X189500D02*
X303650D01*
G01X256251Y399201D02*
X258315D01*
G01X234562D02*
X253181D01*
G01X229428D02*
X231492D01*
G01X189002D02*
X226358D01*
G01X189500Y398000D02*
X303650D01*
G01X256251Y399201D02*
X258315D01*
G01X234562D02*
X253181D01*
G01X229428D02*
X231492D01*
G01X189002D02*
X226358D01*
G01X189500Y398000D02*
X303650D01*
G01X189500D02*
X303650D01*
G01X189500D02*
X303650D01*
G01X256251Y399201D02*
X258315D01*
G01X189500Y398000D02*
X303650D01*
G01X234562Y399201D02*
X253181D01*
G01X189500Y398000D02*
X303650D01*
G01X229428Y399201D02*
X231492D01*
G01X189500Y398000D02*
X303650D01*
G01X189002Y399201D02*
X226358D01*
G01X189500Y398000D02*
X303650D01*
G01X189500D02*
X303650D01*
G01X256251Y399201D02*
X258315D01*
G01X234562D02*
X253181D01*
G01X229428D02*
X231492D01*
G01X189002D02*
X226358D01*
G01X292080Y521239D02*
X206761Y606559D01*
G01X292080Y521239D02*
X206761Y606559D01*
G01X292080Y521239D02*
X206761Y606559D01*
G01X292080Y521239D02*
X206761Y606559D01*
G01X285002Y509299D02*
X190502Y603799D01*
G01X285002Y509299D02*
X190502Y603799D01*
G01X285002Y509299D02*
X190502Y603799D01*
G01X285002Y509299D02*
X190502Y603799D01*
G01X285002Y509299D02*
X190502Y603799D01*
G01X285500Y510500D02*
X214763Y581237D01*
G01X285002Y509299D02*
X190502Y603799D01*
G01X285002Y509299D02*
X190502Y603799D01*
G01X285500Y510500D02*
X214763Y581237D01*
G01X200701Y614318D02*
Y640998D01*
G01X199500Y628168D02*
Y630232D01*
G01Y613820D02*
Y625098D01*
G01X292578Y522440D02*
X200701Y614318D01*
G01X200959Y612361D02*
X199500Y613820D01*
G01X204590Y608730D02*
X203130Y610190D01*
G01X200701Y614318D02*
Y640998D01*
G01Y614318D02*
Y640998D01*
G01X199500Y628168D02*
Y630232D01*
G01X200701Y614318D02*
Y640998D01*
G01X199500Y613820D02*
Y625098D01*
G01X200701Y614318D02*
Y640998D01*
G01X200959Y612361D02*
X199500Y613820D01*
G01X292578Y522440D02*
X200701Y614318D01*
G01X204590Y608730D02*
X203130Y610190D01*
G01X292578Y522440D02*
X200701Y614318D01*
G01X292578Y522440D02*
X200701Y614318D01*
G01D02*
Y640998D01*
G01X199500Y628168D02*
Y630232D01*
G01Y613820D02*
Y625098D01*
G01X292578Y522440D02*
X200701Y614318D01*
G01X200959Y612361D02*
X199500Y613820D01*
G01X204590Y608730D02*
X203130Y610190D01*
G01X200701Y614318D02*
Y640998D01*
G01Y614318D02*
Y640998D01*
G01X199500Y628168D02*
Y630232D01*
G01X200701Y614318D02*
Y640998D01*
G01X199500Y613820D02*
Y625098D01*
G01X200701Y614318D02*
Y640998D01*
G01X200959Y612361D02*
X199500Y613820D01*
G01X292578Y522440D02*
X200701Y614318D01*
G01X204590Y608730D02*
X203130Y610190D01*
G01X292578Y522440D02*
X200701Y614318D01*
G01X292578Y522440D02*
X200701Y614318D01*
G01X192459Y603541D02*
X191000Y605000D01*
G01X196090Y599910D02*
X194630Y601370D01*
G01X199720Y596280D02*
X198261Y597739D01*
G01X208962Y587038D02*
X201891Y594109D01*
G01X212592Y583408D02*
X211133Y584867D01*
G01X192459Y603541D02*
X191000Y605000D01*
G01X196090Y599910D02*
X194630Y601370D01*
G01X199720Y596280D02*
X198261Y597739D01*
G01X208962Y587038D02*
X201891Y594109D01*
G01X212592Y583408D02*
X211133Y584867D01*
G01X195486Y646213D02*
X191500D01*
G01X194988Y645012D02*
X191499D01*
G01X200701Y640998D02*
X195486Y646213D01*
G01X199500Y640500D02*
X194988Y645012D01*
G01X199500Y638436D02*
Y640500D01*
G01Y633302D02*
Y635366D01*
G01X194988Y645012D02*
X191499D01*
G01X195486Y646213D02*
X191500D01*
G01X199500Y640500D02*
X194988Y645012D01*
G01X200701Y640998D02*
X195486Y646213D01*
G01X199500Y638436D02*
Y640500D01*
G01Y633302D02*
Y635366D01*
G01X195486Y646213D02*
X191500D01*
G01X194988Y645012D02*
X191499D01*
G01X200701Y640998D02*
X195486Y646213D01*
G01X199500Y640500D02*
X194988Y645012D01*
G01X199500Y638436D02*
Y640500D01*
G01Y633302D02*
Y635366D01*
G01X194988Y645012D02*
X191499D01*
G01X195486Y646213D02*
X191500D01*
G01X199500Y640500D02*
X194988Y645012D01*
G01X200701Y640998D02*
X195486Y646213D01*
G01X199500Y638436D02*
Y640500D01*
G01Y633302D02*
Y635366D01*
G01X272619Y828630D02*
X190130D01*
G01X303121Y827429D02*
X190628D01*
G01X303121D02*
X190628D01*
G01X303121D02*
X190628D01*
G01X303121D02*
X190628D01*
G01X272619Y828630D02*
X190130D01*
G01X272619D02*
X190130D01*
G01X303121Y827429D02*
X190628D01*
G01X303121D02*
X190628D01*
G01X303121D02*
X190628D01*
G01X272619Y828630D02*
X190130D01*
G01X303121Y827429D02*
X190628D01*
G01X303121D02*
X190628D01*
G01X303121D02*
X190628D01*
G01X303121D02*
X190628D01*
G01X272619Y828630D02*
X190130D01*
G01X303121Y827429D02*
X190628D01*
G01X272619Y828630D02*
X190130D01*
G01X272619D02*
X190130D01*
G01X303121Y827429D02*
X190628D01*
G01X303121D02*
X190628D01*
G01X303121D02*
X190628D01*
G01X303121D02*
X190628D01*
G01X272619Y828630D02*
X190130D01*
G01X261384Y958516D02*
X200000Y1019900D01*
G01X260886Y957315D02*
X223454Y994747D01*
G01X261384Y958516D02*
X200000Y1019900D01*
G01X261384Y958516D02*
X200000Y1019900D01*
G01X261384Y958516D02*
X200000Y1019900D01*
G01X261384Y958516D02*
X200000Y1019900D01*
G01X261384Y958516D02*
X200000Y1019900D01*
G01X260886Y957315D02*
X223454Y994747D01*
G01X261384Y958516D02*
X200000Y1019900D01*
G01X261384Y958516D02*
X200000Y1019900D01*
G01X260886Y957315D02*
X223454Y994747D01*
G01X261384Y958516D02*
X200000Y1019900D01*
G01X261384Y958516D02*
X200000Y1019900D01*
G01X261384Y958516D02*
X200000Y1019900D01*
G01X261384Y958516D02*
X200000Y1019900D01*
G01X261384Y958516D02*
X200000Y1019900D01*
G01X260886Y957315D02*
X223454Y994747D01*
G01X261384Y958516D02*
X200000Y1019900D01*
G01X249802Y944799D02*
X185802Y1008799D01*
G01X249802Y944799D02*
X185802Y1008799D01*
G01X249802Y944799D02*
X185802Y1008799D01*
G01X204262Y992038D02*
X197191Y999109D01*
G01X249802Y944799D02*
X185802Y1008799D01*
G01X207892Y988408D02*
X206433Y989867D01*
G01X249802Y944799D02*
X185802Y1008799D01*
G01X250300Y946000D02*
X210063Y986237D01*
G01X249802Y944799D02*
X185802Y1008799D01*
G01X320000Y946000D02*
X250300D01*
G01X319502Y944799D02*
X249802D01*
G01D02*
X185802Y1008799D01*
G01X204262Y992038D02*
X197191Y999109D01*
G01X207892Y988408D02*
X206433Y989867D01*
G01X250300Y946000D02*
X210063Y986237D01*
G01X319502Y944799D02*
X249802D01*
G01X320000Y946000D02*
X250300D01*
G01X195486Y1051725D02*
X191500D01*
G01X194988Y1050524D02*
X191499D01*
G01X200000Y1047211D02*
X195486Y1051725D01*
G01X198799Y1046713D02*
X194988Y1050524D01*
G01X200000Y1019900D02*
Y1047211D01*
G01X198799Y1019402D02*
Y1046713D01*
G01X201151Y1017050D02*
X198799Y1019402D01*
G01X204781Y1013420D02*
X203322Y1014879D01*
G01X208411Y1009790D02*
X206952Y1011249D01*
G01X217653Y1000548D02*
X210582Y1007619D01*
G01X221284Y996917D02*
X219824Y998377D01*
G01X194988Y1050524D02*
X191499D01*
G01X195486Y1051725D02*
X191500D01*
G01X198799Y1046713D02*
X194988Y1050524D01*
G01X200000Y1047211D02*
X195486Y1051725D01*
G01X198799Y1019402D02*
Y1046713D01*
G01X200000Y1019900D02*
Y1047211D01*
G01X201151Y1017050D02*
X198799Y1019402D01*
G01X204781Y1013420D02*
X203322Y1014879D01*
G01X208411Y1009790D02*
X206952Y1011249D01*
G01X217653Y1000548D02*
X210582Y1007619D01*
G01X221284Y996917D02*
X219824Y998377D01*
G01X195486Y1051725D02*
X191500D01*
G01X194988Y1050524D02*
X191499D01*
G01X200000Y1047211D02*
X195486Y1051725D01*
G01X198799Y1046713D02*
X194988Y1050524D01*
G01X200000Y1019900D02*
Y1047211D01*
G01X198799Y1019402D02*
Y1046713D01*
G01X201151Y1017050D02*
X198799Y1019402D01*
G01X204781Y1013420D02*
X203322Y1014879D01*
G01X208411Y1009790D02*
X206952Y1011249D01*
G01X217653Y1000548D02*
X210582Y1007619D01*
G01X221284Y996917D02*
X219824Y998377D01*
G01X194988Y1050524D02*
X191499D01*
G01X195486Y1051725D02*
X191500D01*
G01X198799Y1046713D02*
X194988Y1050524D01*
G01X200000Y1047211D02*
X195486Y1051725D01*
G01X198799Y1019402D02*
Y1046713D01*
G01X200000Y1019900D02*
Y1047211D01*
G01X201151Y1017050D02*
X198799Y1019402D01*
G01X204781Y1013420D02*
X203322Y1014879D01*
G01X208411Y1009790D02*
X206952Y1011249D01*
G01X217653Y1000548D02*
X210582Y1007619D01*
G01X221284Y996917D02*
X219824Y998377D01*
G01X187759Y1008541D02*
X186300Y1010000D01*
G01X191390Y1004910D02*
X189930Y1006370D01*
G01X195020Y1001280D02*
X193561Y1002739D01*
G01X187759Y1008541D02*
X186300Y1010000D01*
G01X191390Y1004910D02*
X189930Y1006370D01*
G01X195020Y1001280D02*
X193561Y1002739D01*
G01X253299Y1349299D02*
X188299Y1414299D01*
G01X253299Y1349299D02*
X188299Y1414299D01*
G01X253299Y1349299D02*
X188299Y1414299D01*
G01X253299Y1349299D02*
X188299Y1414299D01*
G01X253299Y1349299D02*
X188299Y1414299D01*
G01X253797Y1350500D02*
X216805Y1387492D01*
G01X253299Y1349299D02*
X188299Y1414299D01*
G01X287199Y1350500D02*
X253797D01*
G01X286701Y1349299D02*
X253299D01*
G01D02*
X188299Y1414299D01*
G01X253797Y1350500D02*
X216805Y1387492D01*
G01X286701Y1349299D02*
X253299D01*
G01X287199Y1350500D02*
X253797D01*
G01X190634Y1331705D02*
X188570D01*
G01X294795D02*
X193704D01*
G01X190634D02*
X188570D01*
G01X294795D02*
X193704D01*
G01X190634D02*
X188570D01*
G01X294795D02*
X193704D01*
G01X190634D02*
X188570D01*
G01X294795D02*
X193704D01*
G01X205260Y1421342D02*
X263898Y1362701D01*
G01X207689Y1417213D02*
X206230Y1418673D01*
G01X211319Y1413583D02*
X209860Y1415043D01*
G01X234692Y1390209D02*
X213490Y1411413D01*
G01X238322Y1386579D02*
X236863Y1388038D01*
G01X263400Y1361500D02*
X240493Y1384408D01*
G01X197769Y1428833D02*
X205260Y1421342D01*
G01X204059Y1420844D02*
X196568Y1428335D01*
G01X197769Y1454752D02*
Y1428833D01*
G01X196568Y1428335D02*
Y1454254D01*
G01Y1428335D02*
Y1454254D01*
G01X197769Y1454752D02*
Y1428833D01*
G01X204059Y1420844D02*
X196568Y1428335D01*
G01X197769Y1428833D02*
X205260Y1421342D01*
G01X207689Y1417213D02*
X206230Y1418673D01*
G01X205260Y1421342D02*
X263898Y1362701D01*
G01X211319Y1413583D02*
X209860Y1415043D01*
G01X205260Y1421342D02*
X263898Y1362701D01*
G01X234692Y1390209D02*
X213490Y1411413D01*
G01X205260Y1421342D02*
X263898Y1362701D01*
G01X238322Y1386579D02*
X236863Y1388038D01*
G01X205260Y1421342D02*
X263898Y1362701D01*
G01X263400Y1361500D02*
X240493Y1384408D01*
G01X205260Y1421342D02*
X263898Y1362701D01*
G01X205260Y1421342D02*
X263898Y1362701D01*
G01X207689Y1417213D02*
X206230Y1418673D01*
G01X211319Y1413583D02*
X209860Y1415043D01*
G01X234692Y1390209D02*
X213490Y1411413D01*
G01X238322Y1386579D02*
X236863Y1388038D01*
G01X263400Y1361500D02*
X240493Y1384408D01*
G01X197769Y1428833D02*
X205260Y1421342D01*
G01X204059Y1420844D02*
X196568Y1428335D01*
G01X197769Y1454752D02*
Y1428833D01*
G01X196568Y1428335D02*
Y1454254D01*
G01Y1428335D02*
Y1454254D01*
G01X197769Y1454752D02*
Y1428833D01*
G01X204059Y1420844D02*
X196568Y1428335D01*
G01X197769Y1428833D02*
X205260Y1421342D01*
G01X207689Y1417213D02*
X206230Y1418673D01*
G01X205260Y1421342D02*
X263898Y1362701D01*
G01X211319Y1413583D02*
X209860Y1415043D01*
G01X205260Y1421342D02*
X263898Y1362701D01*
G01X234692Y1390209D02*
X213490Y1411413D01*
G01X205260Y1421342D02*
X263898Y1362701D01*
G01X238322Y1386579D02*
X236863Y1388038D01*
G01X205260Y1421342D02*
X263898Y1362701D01*
G01X263400Y1361500D02*
X240493Y1384408D01*
G01X205260Y1421342D02*
X263898Y1362701D01*
G01X190632Y1413665D02*
X188797Y1415500D01*
G01X194262Y1410035D02*
X192803Y1411494D01*
G01X197892Y1406405D02*
X196433Y1407864D01*
G01X211004Y1393293D02*
X200063Y1404234D01*
G01X214634Y1389663D02*
X213175Y1391122D01*
G01X190632Y1413665D02*
X188797Y1415500D01*
G01X194262Y1410035D02*
X192803Y1411494D01*
G01X197892Y1406405D02*
X196433Y1407864D01*
G01X211004Y1393293D02*
X200063Y1404234D01*
G01X214634Y1389663D02*
X213175Y1391122D01*
G01X195284Y1457237D02*
X197769Y1454752D01*
G01X196568Y1454254D02*
X194786Y1456036D01*
G01X191500Y1457237D02*
X195284D01*
G01X194786Y1456036D02*
X191499D01*
G01X194786D02*
X191499D01*
G01X191500Y1457237D02*
X195284D01*
G01X196568Y1454254D02*
X194786Y1456036D01*
G01X195284Y1457237D02*
X197769Y1454752D01*
G01X195284Y1457237D02*
X197769Y1454752D01*
G01X196568Y1454254D02*
X194786Y1456036D01*
G01X191500Y1457237D02*
X195284D01*
G01X194786Y1456036D02*
X191499D01*
G01X194786D02*
X191499D01*
G01X191500Y1457237D02*
X195284D01*
G01X196568Y1454254D02*
X194786Y1456036D01*
G01X195284Y1457237D02*
X197769Y1454752D01*
G01X207258Y1641299D02*
X206906Y1641651D01*
G01X332801Y1642500D02*
X207756D01*
G01X207258Y1641299D02*
X206906Y1641651D01*
G01X333299Y1641299D02*
X207258D01*
G01D02*
X206906Y1641651D01*
G01X332801Y1642500D02*
X207756D01*
G01X333299Y1641299D02*
X207258D01*
G01X332801Y1642500D02*
X207756D01*
G01X207258Y1641299D02*
X206906Y1641651D01*
G01X332801Y1642500D02*
X207756D01*
G01X207258Y1641299D02*
X206906Y1641651D01*
G01X333299Y1641299D02*
X207258D01*
G01D02*
X206906Y1641651D01*
G01X332801Y1642500D02*
X207756D01*
G01X333299Y1641299D02*
X207258D01*
G01X332801Y1642500D02*
X207756D01*
G01X351301Y1627500D02*
X205699D01*
G01X351799Y1626299D02*
X205201D01*
G01X351799D02*
X205201D01*
G01X351301Y1627500D02*
X205699D01*
G01X201347Y1698429D02*
X283971D01*
G01X201845Y1699630D02*
X284030D01*
G01X201347Y1698429D02*
X283971D01*
G01X201845Y1699630D02*
X284030D01*
G01X201347Y1698429D02*
X283971D01*
G01X201845Y1699630D02*
X284030D01*
G01X201347Y1698429D02*
X283971D01*
G01X201845Y1699630D02*
X284030D01*
G01X201845D02*
X284030D01*
G01X201347Y1698429D02*
X283971D01*
G01X201845Y1699630D02*
X284030D01*
G01X201347Y1698429D02*
X283971D01*
G01X201845Y1699630D02*
X284030D01*
G01X201347Y1698429D02*
X283971D01*
G01X201845Y1699630D02*
X284030D01*
G01X201347Y1698429D02*
X283971D01*
G01X201347D02*
X283971D01*
G01X201845Y1699630D02*
X284030D01*
G01X201845D02*
X284030D01*
G01X201347Y1698429D02*
X283971D01*
G01X285450Y1862749D02*
X191500D01*
G01X197744Y1861548D02*
X191499D01*
G01X202878D02*
X200814D01*
G01X208012D02*
X205948D01*
G01X235539D02*
X211082D01*
G01X240673D02*
X238609D01*
G01X284952D02*
X243743D01*
G01X197744D02*
X191499D01*
G01X285450Y1862749D02*
X191500D01*
G01X202878Y1861548D02*
X200814D01*
G01X285450Y1862749D02*
X191500D01*
G01X208012Y1861548D02*
X205948D01*
G01X285450Y1862749D02*
X191500D01*
G01X235539Y1861548D02*
X211082D01*
G01X285450Y1862749D02*
X191500D01*
G01X240673Y1861548D02*
X238609D01*
G01X285450Y1862749D02*
X191500D01*
G01X284952Y1861548D02*
X243743D01*
G01X285450Y1862749D02*
X191500D01*
G01X285450D02*
X191500D01*
G01X197744Y1861548D02*
X191499D01*
G01X202878D02*
X200814D01*
G01X208012D02*
X205948D01*
G01X235539D02*
X211082D01*
G01X240673D02*
X238609D01*
G01X284952D02*
X243743D01*
G01X197744D02*
X191499D01*
G01X285450Y1862749D02*
X191500D01*
G01X202878Y1861548D02*
X200814D01*
G01X285450Y1862749D02*
X191500D01*
G01X208012Y1861548D02*
X205948D01*
G01X285450Y1862749D02*
X191500D01*
G01X235539Y1861548D02*
X211082D01*
G01X285450Y1862749D02*
X191500D01*
G01X240673Y1861548D02*
X238609D01*
G01X285450Y1862749D02*
X191500D01*
G01X284952Y1861548D02*
X243743D01*
G01X285450Y1862749D02*
X191500D01*
G01X207462Y1821000D02*
X186216D01*
G01X212596D02*
X210532D01*
G01X303500D02*
X215666D01*
G01X207462D02*
X186216D01*
G01X212596D02*
X210532D01*
G01X303500D02*
X215666D01*
G01X338799Y288799D02*
X290701Y240701D01*
G01X340000Y288301D02*
X291199Y239500D01*
G01X340000Y288301D02*
X291199Y239500D01*
G01X338799Y288799D02*
X290701Y240701D01*
G01X338799Y288799D02*
X290701Y240701D01*
G01X340000Y288301D02*
X291199Y239500D01*
G01X340000Y288301D02*
X291199Y239500D01*
G01X338799Y288799D02*
X290701Y240701D01*
G01X263367Y224952D02*
X261303D01*
G01X286705D02*
X266437D01*
G01X291839D02*
X289775D01*
G01X363000Y294414D02*
X292337Y223751D01*
G01X361799Y294912D02*
X291839Y224952D01*
G01X363000Y294414D02*
X292337Y223751D01*
G01X263367Y224952D02*
X261303D01*
G01X286705D02*
X266437D01*
G01X291839D02*
X289775D01*
G01X363000Y294414D02*
X292337Y223751D01*
G01X291839Y224952D02*
X289775D01*
G01X361799Y294912D02*
X291839Y224952D01*
G01X291606Y399201D02*
X303751D01*
G01X286472D02*
X288536D01*
G01X261385D02*
X283402D01*
G01X307901Y399151D02*
X306499D01*
G01X307900Y397950D02*
X306500D01*
G01X310649Y399201D02*
X337301D01*
G01X310750Y398000D02*
X337300D01*
G01X291606Y399201D02*
X303751D01*
G01X286472D02*
X288536D01*
G01X261385D02*
X283402D01*
G01X307900Y397950D02*
X306500D01*
G01X307901Y399151D02*
X306499D01*
G01X310750Y398000D02*
X337300D01*
G01X310649Y399201D02*
X337301D01*
G01X291606D02*
X303751D01*
G01X286472D02*
X288536D01*
G01X261385D02*
X283402D01*
G01X307901Y399151D02*
X306499D01*
G01X307900Y397950D02*
X306500D01*
G01X310649Y399201D02*
X337301D01*
G01X310750Y398000D02*
X337300D01*
G01X291606Y399201D02*
X303751D01*
G01X286472D02*
X288536D01*
G01X261385D02*
X283402D01*
G01X307901Y399151D02*
X306499D01*
G01X307900Y397950D02*
X306500D01*
G01X310649Y399201D02*
X337301D01*
G01X310750Y398000D02*
X337300D01*
G01X291606Y399201D02*
X303751D01*
G01X286472D02*
X288536D01*
G01X261385D02*
X283402D01*
G01X307900Y397950D02*
X306500D01*
G01X307901Y399151D02*
X306499D01*
G01X310750Y398000D02*
X337300D01*
G01X310649Y399201D02*
X337301D01*
G01X291606D02*
X303751D01*
G01X286472D02*
X288536D01*
G01X261385D02*
X283402D01*
G01X307900Y397950D02*
X306500D01*
G01X307901Y399151D02*
X306499D01*
G01X310750Y398000D02*
X337300D01*
G01X310649Y399201D02*
X337301D01*
G01X291606D02*
X303751D01*
G01X286472D02*
X288536D01*
G01X261385D02*
X283402D01*
G01X307901Y399151D02*
X306499D01*
G01X307900Y397950D02*
X306500D01*
G01X310649Y399201D02*
X337301D01*
G01X310750Y398000D02*
X337300D01*
G01X291606Y399201D02*
X303751D01*
G01X286472D02*
X288536D01*
G01X261385D02*
X283402D01*
G01X307900Y397950D02*
X306500D01*
G01X307901Y399151D02*
X306499D01*
G01X310750Y398000D02*
X337300D01*
G01X310649Y399201D02*
X337301D01*
G01X338500Y468500D02*
X319000Y488000D01*
G01X337299Y468002D02*
X318502Y486799D01*
G01X337299Y468002D02*
X318502Y486799D01*
G01X338500Y468500D02*
X319000Y488000D01*
G01X339759Y522440D02*
X292578D01*
G01X339261Y521239D02*
X292080D01*
G01X339261D02*
X292080D01*
G01X339759Y522440D02*
X292578D01*
G01X339759D02*
X292578D01*
G01X339261Y521239D02*
X292080D01*
G01X339261D02*
X292080D01*
G01X339759Y522440D02*
X292578D01*
G01X325500Y510500D02*
X285500D01*
G01X325002Y509299D02*
X285002D01*
G01X374000Y462000D02*
X325500Y510500D01*
G01X372799Y461502D02*
X325002Y509299D01*
G01D02*
X285002D01*
G01X325500Y510500D02*
X285500D01*
G01X372799Y461502D02*
X325002Y509299D01*
G01X374000Y462000D02*
X325500Y510500D01*
G01X361201Y465498D02*
X326216Y500483D01*
G01X360000Y465000D02*
X325718Y499282D01*
G01X360000Y465000D02*
X325718Y499282D01*
G01X361201Y465498D02*
X326216Y500483D01*
G01X361201Y465498D02*
X326216Y500483D01*
G01X360000Y465000D02*
X325718Y499282D01*
G01X360000Y465000D02*
X325718Y499282D01*
G01X361201Y465498D02*
X326216Y500483D01*
G01X277753Y828630D02*
X275689D01*
G01X303080D02*
X280823D01*
G01X307201Y828651D02*
X305899D01*
G01X307200Y827450D02*
X305900D01*
G01X310020Y828630D02*
X336280D01*
G01X309979Y827429D02*
X336321D01*
G01X277753Y828630D02*
X275689D01*
G01X303080D02*
X280823D01*
G01X307200Y827450D02*
X305900D01*
G01X307201Y828651D02*
X305899D01*
G01X309979Y827429D02*
X336321D01*
G01X310020Y828630D02*
X336280D01*
G01X277753D02*
X275689D01*
G01X303080D02*
X280823D01*
G01X307201Y828651D02*
X305899D01*
G01X307200Y827450D02*
X305900D01*
G01X310020Y828630D02*
X336280D01*
G01X309979Y827429D02*
X336321D01*
G01X277753Y828630D02*
X275689D01*
G01X303080D02*
X280823D01*
G01X307201Y828651D02*
X305899D01*
G01X307200Y827450D02*
X305900D01*
G01X310020Y828630D02*
X336280D01*
G01X309979Y827429D02*
X336321D01*
G01X277753Y828630D02*
X275689D01*
G01X303080D02*
X280823D01*
G01X307200Y827450D02*
X305900D01*
G01X307201Y828651D02*
X305899D01*
G01X309979Y827429D02*
X336321D01*
G01X310020Y828630D02*
X336280D01*
G01X277753D02*
X275689D01*
G01X303080D02*
X280823D01*
G01X307200Y827450D02*
X305900D01*
G01X307201Y828651D02*
X305899D01*
G01X309979Y827429D02*
X336321D01*
G01X310020Y828630D02*
X336280D01*
G01X277753D02*
X275689D01*
G01X303080D02*
X280823D01*
G01X307201Y828651D02*
X305899D01*
G01X307200Y827450D02*
X305900D01*
G01X310020Y828630D02*
X336280D01*
G01X309979Y827429D02*
X336321D01*
G01X277753Y828630D02*
X275689D01*
G01X303080D02*
X280823D01*
G01X307200Y827450D02*
X305900D01*
G01X307201Y828651D02*
X305899D01*
G01X309979Y827429D02*
X336321D01*
G01X310020Y828630D02*
X336280D01*
G01X338500Y898860D02*
X315860Y921500D01*
G01X337299Y898362D02*
X315362Y920299D01*
G01X337299Y898362D02*
X315362Y920299D01*
G01X338500Y898860D02*
X315860Y921500D01*
G01X333984Y958516D02*
X261384D01*
G01X333486Y957315D02*
X260886D01*
G01X333486D02*
X260886D01*
G01X333984Y958516D02*
X261384D01*
G01X333984D02*
X261384D01*
G01X333486Y957315D02*
X260886D01*
G01X333486D02*
X260886D01*
G01X333984Y958516D02*
X261384D01*
G01X374000Y892000D02*
X320000Y946000D01*
G01X372799Y891502D02*
X319502Y944799D01*
G01X372799Y891502D02*
X319502Y944799D01*
G01X374000Y892000D02*
X320000Y946000D01*
G01X321299Y935701D02*
X361201Y895799D01*
G01X320801Y934500D02*
X360000Y895301D01*
G01X320801Y934500D02*
X360000Y895301D01*
G01X321299Y935701D02*
X361201Y895799D01*
G01X321299Y935701D02*
X361201Y895799D01*
G01X320801Y934500D02*
X360000Y895301D01*
G01X320801Y934500D02*
X360000Y895301D01*
G01X321299Y935701D02*
X361201Y895799D01*
G01X300470Y1200130D02*
X303830D01*
G01X299972Y1198929D02*
X303771D01*
G01X297199Y1203401D02*
X300470Y1200130D01*
G01X296701Y1202200D02*
X299972Y1198929D01*
G01X307901Y1200101D02*
X306599D01*
G01X307900Y1198900D02*
X306600D01*
G01X310670Y1200130D02*
X336980D01*
G01X310729Y1198929D02*
X337021D01*
G01X299972D02*
X303771D01*
G01X300470Y1200130D02*
X303830D01*
G01X296701Y1202200D02*
X299972Y1198929D01*
G01X297199Y1203401D02*
X300470Y1200130D01*
G01X307900Y1198900D02*
X306600D01*
G01X307901Y1200101D02*
X306599D01*
G01X310729Y1198929D02*
X337021D01*
G01X310670Y1200130D02*
X336980D01*
G01X300470D02*
X303830D01*
G01X299972Y1198929D02*
X303771D01*
G01X297199Y1203401D02*
X300470Y1200130D01*
G01X296701Y1202200D02*
X299972Y1198929D01*
G01X307901Y1200101D02*
X306599D01*
G01X307900Y1198900D02*
X306600D01*
G01X310670Y1200130D02*
X336980D01*
G01X310729Y1198929D02*
X337021D01*
G01X300470Y1200130D02*
X303830D01*
G01X299972Y1198929D02*
X303771D01*
G01X297199Y1203401D02*
X300470Y1200130D01*
G01X296701Y1202200D02*
X299972Y1198929D01*
G01X307901Y1200101D02*
X306599D01*
G01X307900Y1198900D02*
X306600D01*
G01X310670Y1200130D02*
X336980D01*
G01X310729Y1198929D02*
X337021D01*
G01X299972D02*
X303771D01*
G01X300470Y1200130D02*
X303830D01*
G01X296701Y1202200D02*
X299972Y1198929D01*
G01X297199Y1203401D02*
X300470Y1200130D01*
G01X307900Y1198900D02*
X306600D01*
G01X307901Y1200101D02*
X306599D01*
G01X310729Y1198929D02*
X337021D01*
G01X310670Y1200130D02*
X336980D01*
G01X299972Y1198929D02*
X303771D01*
G01X300470Y1200130D02*
X303830D01*
G01X296701Y1202200D02*
X299972Y1198929D01*
G01X297199Y1203401D02*
X300470Y1200130D01*
G01X307900Y1198900D02*
X306600D01*
G01X307901Y1200101D02*
X306599D01*
G01X310729Y1198929D02*
X337021D01*
G01X310670Y1200130D02*
X336980D01*
G01X300470D02*
X303830D01*
G01X299972Y1198929D02*
X303771D01*
G01X297199Y1203401D02*
X300470Y1200130D01*
G01X296701Y1202200D02*
X299972Y1198929D01*
G01X307901Y1200101D02*
X306599D01*
G01X307900Y1198900D02*
X306600D01*
G01X310670Y1200130D02*
X336980D01*
G01X310729Y1198929D02*
X337021D01*
G01X299972D02*
X303771D01*
G01X300470Y1200130D02*
X303830D01*
G01X296701Y1202200D02*
X299972Y1198929D01*
G01X297199Y1203401D02*
X300470Y1200130D01*
G01X307900Y1198900D02*
X306600D01*
G01X307901Y1200101D02*
X306599D01*
G01X310729Y1198929D02*
X337021D01*
G01X310670Y1200130D02*
X336980D01*
G01X338500Y1270000D02*
X289000Y1319500D01*
G01X337299Y1269502D02*
X288502Y1318299D01*
G01X337299Y1269502D02*
X288502Y1318299D01*
G01X338500Y1270000D02*
X289000Y1319500D01*
G01X301498Y1362701D02*
X396701Y1267498D01*
G01X395500Y1267000D02*
X301000Y1361500D01*
G01X395500Y1267000D02*
X301000Y1361500D01*
G01X301498Y1362701D02*
X396701Y1267498D01*
G01X301498Y1362701D02*
X396701Y1267498D01*
G01X395500Y1267000D02*
X301000Y1361500D01*
G01X395500Y1267000D02*
X301000Y1361500D01*
G01X301498Y1362701D02*
X396701Y1267498D01*
G01X374000Y1263699D02*
X287199Y1350500D01*
G01X372799Y1263201D02*
X286701Y1349299D01*
G01X372799Y1263201D02*
X286701Y1349299D01*
G01X374000Y1263699D02*
X287199Y1350500D01*
G01X361201Y1266998D02*
X295293Y1332906D01*
G01X360000Y1266500D02*
X294795Y1331705D01*
G01X360000Y1266500D02*
X294795Y1331705D01*
G01X361201Y1266998D02*
X295293Y1332906D01*
G01X361201Y1266998D02*
X295293Y1332906D01*
G01X360000Y1266500D02*
X294795Y1331705D01*
G01X360000Y1266500D02*
X294795Y1331705D01*
G01X361201Y1266998D02*
X295293Y1332906D01*
G01X263898Y1362701D02*
X301498D01*
G01X301000Y1361500D02*
X263400D01*
G01X301000D02*
X263400D01*
G01X263898Y1362701D02*
X301498D01*
G01X263898D02*
X301498D01*
G01X301000Y1361500D02*
X263400D01*
G01X301000D02*
X263400D01*
G01X263898Y1362701D02*
X301498D01*
G01X329120Y1698630D02*
X348954D01*
G01X329079Y1697429D02*
X348954D01*
G01X311670Y1698630D02*
X328080D01*
G01X311729Y1697429D02*
X328121D01*
G01X295031Y1698630D02*
X304830D01*
G01X295529Y1697429D02*
X304771D01*
G01X293449Y1697048D02*
X295031Y1698630D01*
G01X294650Y1696550D02*
X295529Y1697429D01*
G01X293449Y1694449D02*
Y1697048D01*
G01X294650Y1694350D02*
Y1696550D01*
G01X308901Y1698601D02*
X307599D01*
G01X308900Y1697400D02*
X307600D01*
G01X329120Y1698630D02*
X348954D01*
G01X329079Y1697429D02*
X348954D01*
G01X311670Y1698630D02*
X328080D01*
G01X311729Y1697429D02*
X328121D01*
G01X295031Y1698630D02*
X304830D01*
G01X295529Y1697429D02*
X304771D01*
G01X293449Y1697048D02*
X295031Y1698630D01*
G01X294650Y1696550D02*
X295529Y1697429D01*
G01X293449Y1694449D02*
Y1697048D01*
G01X294650Y1694350D02*
Y1696550D01*
G01X308901Y1698601D02*
X307599D01*
G01X308900Y1697400D02*
X307600D01*
G01X329120Y1698630D02*
X348954D01*
G01X329079Y1697429D02*
X348954D01*
G01X311670Y1698630D02*
X328080D01*
G01X311729Y1697429D02*
X328121D01*
G01X295031Y1698630D02*
X304830D01*
G01X295529Y1697429D02*
X304771D01*
G01X293449Y1697048D02*
X295031Y1698630D01*
G01X294650Y1696550D02*
X295529Y1697429D01*
G01X293449Y1694449D02*
Y1697048D01*
G01X294650Y1694350D02*
Y1696550D01*
G01X308901Y1698601D02*
X307599D01*
G01X308900Y1697400D02*
X307600D01*
G01X329120Y1698630D02*
X348954D01*
G01X329079Y1697429D02*
X348954D01*
G01X311670Y1698630D02*
X328080D01*
G01X311729Y1697429D02*
X328121D01*
G01X295031Y1698630D02*
X304830D01*
G01X295529Y1697429D02*
X304771D01*
G01X293449Y1697048D02*
X295031Y1698630D01*
G01X294650Y1696550D02*
X295529Y1697429D01*
G01X293449Y1694449D02*
Y1697048D01*
G01X294650Y1694350D02*
Y1696550D01*
G01X308901Y1698601D02*
X307599D01*
G01X308900Y1697400D02*
X307600D01*
G01X329079Y1697429D02*
X348954D01*
G01X329120Y1698630D02*
X348954D01*
G01X311729Y1697429D02*
X328121D01*
G01X311670Y1698630D02*
X328080D01*
G01X295529Y1697429D02*
X304771D01*
G01X295031Y1698630D02*
X304830D01*
G01X294650Y1696550D02*
X295529Y1697429D01*
G01X293449Y1697048D02*
X295031Y1698630D01*
G01X294650Y1694350D02*
Y1696550D01*
G01X293449Y1694449D02*
Y1697048D01*
G01X308900Y1697400D02*
X307600D01*
G01X308901Y1698601D02*
X307599D01*
G01X329079Y1697429D02*
X348954D01*
G01X329120Y1698630D02*
X348954D01*
G01X311729Y1697429D02*
X328121D01*
G01X311670Y1698630D02*
X328080D01*
G01X295529Y1697429D02*
X304771D01*
G01X295031Y1698630D02*
X304830D01*
G01X294650Y1696550D02*
X295529Y1697429D01*
G01X293449Y1697048D02*
X295031Y1698630D01*
G01X294650Y1694350D02*
Y1696550D01*
G01X293449Y1694449D02*
Y1697048D01*
G01X308900Y1697400D02*
X307600D01*
G01X308901Y1698601D02*
X307599D01*
G01X329079Y1697429D02*
X348954D01*
G01X329120Y1698630D02*
X348954D01*
G01X311729Y1697429D02*
X328121D01*
G01X311670Y1698630D02*
X328080D01*
G01X295529Y1697429D02*
X304771D01*
G01X295031Y1698630D02*
X304830D01*
G01X294650Y1696550D02*
X295529Y1697429D01*
G01X293449Y1697048D02*
X295031Y1698630D01*
G01X294650Y1694350D02*
Y1696550D01*
G01X293449Y1694449D02*
Y1697048D01*
G01X308900Y1697400D02*
X307600D01*
G01X308901Y1698601D02*
X307599D01*
G01X329079Y1697429D02*
X348954D01*
G01X329120Y1698630D02*
X348954D01*
G01X311729Y1697429D02*
X328121D01*
G01X311670Y1698630D02*
X328080D01*
G01X295529Y1697429D02*
X304771D01*
G01X295031Y1698630D02*
X304830D01*
G01X294650Y1696550D02*
X295529Y1697429D01*
G01X293449Y1697048D02*
X295031Y1698630D01*
G01X294650Y1694350D02*
Y1696550D01*
G01X293449Y1694449D02*
Y1697048D01*
G01X308900Y1697400D02*
X307600D01*
G01X308901Y1698601D02*
X307599D01*
G01X329120Y1698630D02*
X348954D01*
G01X329079Y1697429D02*
X348954D01*
G01X311670Y1698630D02*
X328080D01*
G01X311729Y1697429D02*
X328121D01*
G01X295031Y1698630D02*
X304830D01*
G01X295529Y1697429D02*
X304771D01*
G01X293449Y1697048D02*
X295031Y1698630D01*
G01X294650Y1696550D02*
X295529Y1697429D01*
G01X293449Y1694449D02*
Y1697048D01*
G01X294650Y1694350D02*
Y1696550D01*
G01X308901Y1698601D02*
X307599D01*
G01X308900Y1697400D02*
X307600D01*
G01X329079Y1697429D02*
X348954D01*
G01X329120Y1698630D02*
X348954D01*
G01X311729Y1697429D02*
X328121D01*
G01X311670Y1698630D02*
X328080D01*
G01X295529Y1697429D02*
X304771D01*
G01X295031Y1698630D02*
X304830D01*
G01X294650Y1696550D02*
X295529Y1697429D01*
G01X293449Y1697048D02*
X295031Y1698630D01*
G01X294650Y1694350D02*
Y1696550D01*
G01X293449Y1694449D02*
Y1697048D01*
G01X308900Y1697400D02*
X307600D01*
G01X308901Y1698601D02*
X307599D01*
G01X303002Y1819799D02*
X337299Y1785502D01*
G01X303002Y1819799D02*
X337299Y1785502D01*
G01X361201Y1786998D02*
X285450Y1862749D01*
G01X360000Y1786500D02*
X284952Y1861548D01*
G01X360000Y1786500D02*
X284952Y1861548D01*
G01X361201Y1786998D02*
X285450Y1862749D01*
G01X361201Y1786998D02*
X285450Y1862749D01*
G01X360000Y1786500D02*
X284952Y1861548D01*
G01X360000Y1786500D02*
X284952Y1861548D01*
G01X361201Y1786998D02*
X285450Y1862749D01*
G01X338500Y1786000D02*
X303500Y1821000D01*
G01X338500Y1786000D02*
X303500Y1821000D01*
G01X374299Y358498D02*
Y265799D01*
G01X375500Y358000D02*
Y265301D01*
G01Y358000D02*
Y265301D01*
G01X374299Y358498D02*
Y265799D01*
G01Y358498D02*
Y265799D01*
G01X375500Y358000D02*
Y265301D01*
G01Y358000D02*
Y265301D01*
G01X374299Y358498D02*
Y265799D01*
G01X338799Y358198D02*
Y288799D01*
G01X340000Y357700D02*
Y288301D01*
G01Y357700D02*
Y288301D01*
G01X338799Y358198D02*
Y288799D01*
G01Y358198D02*
Y288799D01*
G01X340000Y357700D02*
Y288301D01*
G01Y357700D02*
Y288301D01*
G01X338799Y358198D02*
Y288799D01*
G01X361799Y355502D02*
Y294912D01*
G01X363000Y356000D02*
Y294414D01*
G01Y356000D02*
Y294414D01*
G01X361799Y355502D02*
Y294912D01*
G01X399000Y354000D02*
Y267199D01*
G01X400201Y354498D02*
Y266701D01*
G01Y354498D02*
Y266701D01*
G01X399000Y354000D02*
Y267199D01*
G01X356899Y372399D02*
Y369149D01*
G01X358100Y371901D02*
Y369150D01*
G01X363492Y378992D02*
X356899Y372399D01*
G01X364693Y378494D02*
X358100Y371901D01*
G01X363492Y379618D02*
Y378992D01*
G01X364693Y379500D02*
Y378494D01*
G01X355600Y378500D02*
Y379300D01*
G01X356801Y379196D02*
Y378002D01*
G01X352930Y375830D02*
X355600Y378500D01*
G01X356801Y378002D02*
X349798Y370999D01*
G01X349300Y372200D02*
X350759Y373659D01*
G01X356801Y378002D02*
X349798Y370999D01*
G01X343501Y372200D02*
X349300D01*
G01X349798Y370999D02*
X343999D01*
G01X341899Y370598D02*
X343501Y372200D01*
G01X343999Y370999D02*
X343100Y370100D01*
G01X341899Y368999D02*
Y370598D01*
G01X343100Y370100D02*
Y369150D01*
G01Y370100D02*
Y369150D01*
G01X341899Y368999D02*
Y370598D01*
G01X343999Y370999D02*
X343100Y370100D01*
G01X341899Y370598D02*
X343501Y372200D01*
G01X349798Y370999D02*
X343999D01*
G01X343501Y372200D02*
X349300D01*
G01X356801Y378002D02*
X349798Y370999D01*
G01X352930Y375830D02*
X355600Y378500D01*
G01X349300Y372200D02*
X350759Y373659D01*
G01X356801Y379196D02*
Y378002D01*
G01X355600Y378500D02*
Y379300D01*
G01X358100Y371901D02*
Y369150D01*
G01X356899Y372399D02*
Y369149D01*
G01X364693Y378494D02*
X358100Y371901D01*
G01X363492Y378992D02*
X356899Y372399D01*
G01X364693Y379500D02*
Y378494D01*
G01X363492Y379618D02*
Y378992D01*
G01X377399Y373402D02*
Y369149D01*
G01X378600Y373900D02*
Y369150D01*
G01X373335Y377466D02*
X377399Y373402D01*
G01X374536Y377964D02*
X378600Y373900D01*
G01X373335Y379620D02*
Y377466D01*
G01X374536Y379616D02*
Y377964D01*
G01X378600Y373900D02*
Y369150D01*
G01X377399Y373402D02*
Y369149D01*
G01X374536Y377964D02*
X378600Y373900D01*
G01X373335Y377466D02*
X377399Y373402D01*
G01X374536Y379616D02*
Y377964D01*
G01X373335Y379620D02*
Y377466D01*
G01X381210Y377292D02*
Y378954D01*
G01X382411D02*
Y377790D01*
G01X382900Y375601D02*
X381210Y377292D01*
G01X382411Y377790D02*
X387301Y372900D01*
G01X386803Y371699D02*
X382900Y375601D01*
G01X382411Y377790D02*
X387301Y372900D01*
G01X391431Y371699D02*
X386803D01*
G01X387301Y372900D02*
X391929D01*
G01X392399Y370731D02*
X391431Y371699D01*
G01X391929Y372900D02*
X393600Y371229D01*
G01X392399Y369149D02*
Y370731D01*
G01X393600Y371229D02*
Y369150D01*
G01Y371229D02*
Y369150D01*
G01X392399Y369149D02*
Y370731D01*
G01X391929Y372900D02*
X393600Y371229D01*
G01X392399Y370731D02*
X391431Y371699D01*
G01X387301Y372900D02*
X391929D01*
G01X391431Y371699D02*
X386803D01*
G01X382411Y377790D02*
X387301Y372900D01*
G01X382900Y375601D02*
X381210Y377292D01*
G01X386803Y371699D02*
X382900Y375601D01*
G01X382411Y378954D02*
Y377790D01*
G01X381210Y377292D02*
Y378954D01*
G01X338299Y399201D02*
X348881D01*
G01X338300Y398000D02*
X348383D01*
G01X338300D02*
X348383D01*
G01X338299Y399201D02*
X348881D01*
G01X338299D02*
X348881D01*
G01X338300Y398000D02*
X348383D01*
G01X338299Y399201D02*
X348881D01*
G01X338300Y398000D02*
X348383D01*
G01X338300D02*
X348383D01*
G01X338299Y399201D02*
X348881D01*
G01X338300Y398000D02*
X348383D01*
G01X338299Y399201D02*
X348881D01*
G01X341899Y361298D02*
X338799Y358198D01*
G01X343100Y360800D02*
X340000Y357700D01*
G01X341899Y362851D02*
Y361298D01*
G01X343100Y362850D02*
Y360800D01*
G01D02*
X340000Y357700D01*
G01X341899Y361298D02*
X338799Y358198D01*
G01X343100Y362850D02*
Y360800D01*
G01X341899Y362851D02*
Y361298D01*
G01D02*
X338799Y358198D01*
G01X343100Y360800D02*
X340000Y357700D01*
G01X341899Y362851D02*
Y361298D01*
G01X343100Y362850D02*
Y360800D01*
G01D02*
X340000Y357700D01*
G01X341899Y361298D02*
X338799Y358198D01*
G01X343100Y362850D02*
Y360800D01*
G01X341899Y362851D02*
Y361298D01*
G01X357099Y360202D02*
X361799Y355502D01*
G01X358300Y360700D02*
X363000Y356000D01*
G01X357099Y362651D02*
Y360202D01*
G01X358300Y363050D02*
Y360700D01*
G01D02*
X363000Y356000D01*
G01X357099Y360202D02*
X361799Y355502D01*
G01X358300Y363050D02*
Y360700D01*
G01X357099Y362651D02*
Y360202D01*
G01X377299Y361498D02*
X374299Y358498D01*
G01X378500Y361000D02*
X375500Y358000D01*
G01X377299Y362951D02*
Y361498D01*
G01X378500Y362750D02*
Y361000D01*
G01D02*
X375500Y358000D01*
G01X377299Y361498D02*
X374299Y358498D01*
G01X378500Y362750D02*
Y361000D01*
G01X377299Y362951D02*
Y361498D01*
G01D02*
X374299Y358498D01*
G01X378500Y361000D02*
X375500Y358000D01*
G01X377299Y362951D02*
Y361498D01*
G01X378500Y362750D02*
Y361000D01*
G01D02*
X375500Y358000D01*
G01X377299Y361498D02*
X374299Y358498D01*
G01X378500Y362750D02*
Y361000D01*
G01X377299Y362951D02*
Y361498D01*
G01X392299Y360701D02*
X399000Y354000D01*
G01X393500Y361199D02*
X400201Y354498D01*
G01X392299Y362951D02*
Y360701D01*
G01X393500Y362750D02*
Y361199D01*
G01D02*
X400201Y354498D01*
G01X392299Y360701D02*
X399000Y354000D01*
G01X393500Y362750D02*
Y361199D01*
G01X392299Y362951D02*
Y360701D01*
G01X338299Y399201D02*
X348881D01*
G01X338300Y398000D02*
X348383D01*
G01X338300D02*
X348383D01*
G01X338299Y399201D02*
X348881D01*
G01X393600Y428401D02*
Y430850D01*
G01X392399Y428899D02*
Y430851D01*
G01X390699Y425500D02*
X393600Y428401D01*
G01X390201Y426701D02*
X392399Y428899D01*
G01X387000Y425500D02*
X390699D01*
G01X386502Y426701D02*
X390201D01*
G01X382410Y420910D02*
X387000Y425500D01*
G01X381209Y421408D02*
X386502Y426701D01*
G01X382410Y420385D02*
Y420910D01*
G01X381209Y420500D02*
Y421408D01*
G01X392399Y428899D02*
Y430851D01*
G01X393600Y428401D02*
Y430850D01*
G01X390201Y426701D02*
X392399Y428899D01*
G01X390699Y425500D02*
X393600Y428401D01*
G01X386502Y426701D02*
X390201D01*
G01X387000Y425500D02*
X390699D01*
G01X381209Y421408D02*
X386502Y426701D01*
G01X382410Y420910D02*
X387000Y425500D01*
G01X381209Y420500D02*
Y421408D01*
G01X382410Y420385D02*
Y420910D01*
G01X378600Y427600D02*
Y430850D01*
G01X377399Y428098D02*
Y430851D01*
G01X374538Y423538D02*
X378600Y427600D01*
G01X373337Y424036D02*
X377399Y428098D01*
G01X374538Y420882D02*
Y423538D01*
G01X373337Y420882D02*
Y424036D01*
G01X377399Y428098D02*
Y430851D01*
G01X378600Y427600D02*
Y430850D01*
G01X373337Y424036D02*
X377399Y428098D01*
G01X374538Y423538D02*
X378600Y427600D01*
G01X373337Y420882D02*
Y424036D01*
G01X374538Y420882D02*
Y423538D01*
G01X358100Y428400D02*
Y430850D01*
G01X356899Y427902D02*
Y430851D01*
G01X364695Y421805D02*
X358100Y428400D01*
G01X363494Y421307D02*
X356899Y427902D01*
G01X364695Y420500D02*
Y421805D01*
G01X363494Y420500D02*
Y421307D01*
G01X356899Y427902D02*
Y430851D01*
G01X358100Y428400D02*
Y430850D01*
G01X363494Y421307D02*
X356899Y427902D01*
G01X364695Y421805D02*
X358100Y428400D01*
G01X363494Y420500D02*
Y421307D01*
G01X364695Y420500D02*
Y421805D01*
G01X343100Y429599D02*
Y430850D01*
G01X341899Y431001D02*
Y429101D01*
G01X345099Y427600D02*
X343100Y429599D01*
G01X341899Y429101D02*
X344601Y426399D01*
G01X350899Y427600D02*
X345099D01*
G01X344601Y426399D02*
X350401D01*
G01X356801Y421698D02*
X350899Y427600D01*
G01X354031Y422769D02*
X355600Y421200D01*
G01X350401Y426399D02*
X351860Y424940D01*
G01X356801Y420499D02*
Y421698D01*
G01X355600Y421200D02*
Y420600D01*
G01Y421200D02*
Y420600D01*
G01X356801Y420499D02*
Y421698D01*
G01X354031Y422769D02*
X355600Y421200D01*
G01X356801Y421698D02*
X350899Y427600D01*
G01X350401Y426399D02*
X351860Y424940D01*
G01X356801Y421698D02*
X350899Y427600D01*
G01X344601Y426399D02*
X350401D01*
G01X350899Y427600D02*
X345099D01*
G01X341899Y429101D02*
X344601Y426399D01*
G01X345099Y427600D02*
X343100Y429599D01*
G01X341899Y431001D02*
Y429101D01*
G01X343100Y429599D02*
Y430850D01*
G01X396701Y465498D02*
X339759Y522440D01*
G01X395500Y465000D02*
X339261Y521239D01*
G01X396701Y441702D02*
Y465498D01*
G01X395500Y442200D02*
Y465000D01*
G01X393501Y438502D02*
X396701Y441702D01*
G01X392300Y439000D02*
X395500Y442200D01*
G01X393501Y437249D02*
Y438502D01*
G01X392300Y437050D02*
Y439000D01*
G01X395500Y465000D02*
X339261Y521239D01*
G01X396701Y465498D02*
X339759Y522440D01*
G01X395500Y442200D02*
Y465000D01*
G01X396701Y441702D02*
Y465498D01*
G01X392300Y439000D02*
X395500Y442200D01*
G01X393501Y438502D02*
X396701Y441702D01*
G01X392300Y437050D02*
Y439000D01*
G01X393501Y437249D02*
Y438502D01*
G01X396701Y465498D02*
X339759Y522440D01*
G01X395500Y465000D02*
X339261Y521239D01*
G01X396701Y441702D02*
Y465498D01*
G01X395500Y442200D02*
Y465000D01*
G01X393501Y438502D02*
X396701Y441702D01*
G01X392300Y439000D02*
X395500Y442200D01*
G01X393501Y437249D02*
Y438502D01*
G01X392300Y437050D02*
Y439000D01*
G01X395500Y465000D02*
X339261Y521239D01*
G01X396701Y465498D02*
X339759Y522440D01*
G01X395500Y442200D02*
Y465000D01*
G01X396701Y441702D02*
Y465498D01*
G01X392300Y439000D02*
X395500Y442200D01*
G01X393501Y438502D02*
X396701Y441702D01*
G01X392300Y437050D02*
Y439000D01*
G01X393501Y437249D02*
Y438502D01*
G01X374000Y444000D02*
Y462000D01*
G01X372799Y443502D02*
Y461502D01*
G01X378701Y439299D02*
X374000Y444000D01*
G01X377500Y438801D02*
X372799Y443502D01*
G01X378701Y437049D02*
Y439299D01*
G01X377500Y437250D02*
Y438801D01*
G01X372799Y443502D02*
Y461502D01*
G01X374000Y444000D02*
Y462000D01*
G01X377500Y438801D02*
X372799Y443502D01*
G01X378701Y439299D02*
X374000Y444000D01*
G01X377500Y437250D02*
Y438801D01*
G01X378701Y437049D02*
Y439299D01*
G01X361201Y441502D02*
Y465498D01*
G01X360000Y442000D02*
Y465000D01*
G01X358001Y438302D02*
X361201Y441502D01*
G01X356800Y438800D02*
X360000Y442000D01*
G01X358001Y437249D02*
Y438302D01*
G01X356800Y437050D02*
Y438800D01*
G01X360000Y442000D02*
Y465000D01*
G01X361201Y441502D02*
Y465498D01*
G01X356800Y438800D02*
X360000Y442000D01*
G01X358001Y438302D02*
X361201Y441502D01*
G01X356800Y437050D02*
Y438800D01*
G01X358001Y437249D02*
Y438302D01*
G01X338500Y444000D02*
Y468500D01*
G01X337299Y443502D02*
Y468002D01*
G01X343051Y439449D02*
X338500Y444000D01*
G01X341850Y438951D02*
X337299Y443502D01*
G01X343051Y437099D02*
Y439449D01*
G01X341850Y437100D02*
Y438951D01*
G01X361201Y441502D02*
Y465498D01*
G01X360000Y442000D02*
Y465000D01*
G01X358001Y438302D02*
X361201Y441502D01*
G01X356800Y438800D02*
X360000Y442000D01*
G01X358001Y437249D02*
Y438302D01*
G01X356800Y437050D02*
Y438800D01*
G01X360000Y442000D02*
Y465000D01*
G01X361201Y441502D02*
Y465498D01*
G01X356800Y438800D02*
X360000Y442000D01*
G01X358001Y438302D02*
X361201Y441502D01*
G01X356800Y437050D02*
Y438800D01*
G01X358001Y437249D02*
Y438302D01*
G01X337299Y443502D02*
Y468002D01*
G01X338500Y444000D02*
Y468500D01*
G01X341850Y438951D02*
X337299Y443502D01*
G01X343051Y439449D02*
X338500Y444000D01*
G01X341850Y437100D02*
Y438951D01*
G01X343051Y437099D02*
Y439449D01*
G01X367799Y680402D02*
X863402Y184799D01*
G01X369000Y680900D02*
X840137Y209763D01*
G01X367799Y788498D02*
Y680402D01*
G01X369000Y788000D02*
Y680900D01*
G01X367799Y680402D02*
X863402Y184799D01*
G01X367799Y680402D02*
X863402Y184799D01*
G01X367799Y680402D02*
X863402Y184799D01*
G01X367799Y680402D02*
X863402Y184799D01*
G01X367799Y680402D02*
X863402Y184799D01*
G01X369000Y680900D02*
X840137Y209763D01*
G01X367799Y680402D02*
X863402Y184799D01*
G01X369000Y788000D02*
Y680900D01*
G01X367799Y788498D02*
Y680402D01*
G01D02*
X863402Y184799D01*
G01X369000Y680900D02*
X840137Y209763D01*
G01X367799Y788498D02*
Y680402D01*
G01X369000Y788000D02*
Y680900D01*
G01X367799Y680402D02*
X863402Y184799D01*
G01X367799Y680402D02*
X863402Y184799D01*
G01X367799Y680402D02*
X863402Y184799D01*
G01X367799Y680402D02*
X863402Y184799D01*
G01X367799Y680402D02*
X863402Y184799D01*
G01X369000Y680900D02*
X840137Y209763D01*
G01X367799Y680402D02*
X863402Y184799D01*
G01X369000Y788000D02*
Y680900D01*
G01X367799Y788498D02*
Y680402D01*
G01X390500Y677000D02*
X861001Y206499D01*
G01X391701Y677498D02*
X829184Y240015D01*
G01X390500Y786000D02*
Y677000D01*
G01X391701Y786498D02*
Y677498D01*
G01X390500Y677000D02*
X861001Y206499D01*
G01X390500Y677000D02*
X861001Y206499D01*
G01X390500Y677000D02*
X861001Y206499D01*
G01X390500Y677000D02*
X861001Y206499D01*
G01X390500Y677000D02*
X861001Y206499D01*
G01X391701Y677498D02*
X829184Y240015D01*
G01X390500Y677000D02*
X861001Y206499D01*
G01X391701Y786498D02*
Y677498D01*
G01X390500Y786000D02*
Y677000D01*
G01X370899Y791598D02*
X367799Y788498D01*
G01X372100Y791100D02*
X369000Y788000D01*
G01X370899Y792851D02*
Y791598D01*
G01X372100Y792850D02*
Y791100D01*
G01D02*
X369000Y788000D01*
G01X370899Y791598D02*
X367799Y788498D01*
G01X372100Y792850D02*
Y791100D01*
G01X370899Y792851D02*
Y791598D01*
G01Y804598D02*
Y799149D01*
G01X372100Y804100D02*
Y799150D01*
G01X373335Y807034D02*
X370899Y804598D01*
G01X374536Y806536D02*
X372100Y804100D01*
G01X373335Y809500D02*
Y807034D01*
G01X374536Y809500D02*
Y806536D01*
G01X372100Y804100D02*
Y799150D01*
G01X370899Y804598D02*
Y799149D01*
G01X374536Y806536D02*
X372100Y804100D01*
G01X373335Y807034D02*
X370899Y804598D01*
G01X374536Y809500D02*
Y806536D01*
G01X373335Y809500D02*
Y807034D01*
G01X385899Y800402D02*
Y799149D01*
G01X387100Y800900D02*
Y799150D01*
G01X381329Y804972D02*
X385899Y800402D01*
G01X382530Y805470D02*
X387100Y800900D01*
G01X381329Y809496D02*
Y804972D01*
G01X382530Y809735D02*
Y805470D01*
G01X387100Y800900D02*
Y799150D01*
G01X385899Y800402D02*
Y799149D01*
G01X382530Y805470D02*
X387100Y800900D01*
G01X381329Y804972D02*
X385899Y800402D01*
G01X382530Y809735D02*
Y805470D01*
G01X381329Y809496D02*
Y804972D01*
G01X398401Y806400D02*
X400850D01*
G01X398899Y807601D02*
X400851D01*
G01X396799Y808002D02*
X398401Y806400D01*
G01X398000Y808500D02*
X398899Y807601D01*
G01X396799Y811701D02*
Y808002D01*
G01X398000Y812199D02*
Y808500D01*
G01X390910Y817590D02*
X396799Y811701D01*
G01X391408Y818791D02*
X398000Y812199D01*
G01X390385Y817590D02*
X390910D01*
G01X390384Y818791D02*
X391408D01*
G01X398899Y807601D02*
X400851D01*
G01X398401Y806400D02*
X400850D01*
G01X398000Y808500D02*
X398899Y807601D01*
G01X396799Y808002D02*
X398401Y806400D01*
G01X398000Y812199D02*
Y808500D01*
G01X396799Y811701D02*
Y808002D01*
G01X391408Y818791D02*
X398000Y812199D01*
G01X390910Y817590D02*
X396799Y811701D01*
G01X390384Y818791D02*
X391408D01*
G01X390385Y817590D02*
X390910D01*
G01X393538Y825462D02*
X390382D01*
G01X394036Y826663D02*
X390382D01*
G01X397701Y821299D02*
X393538Y825462D01*
G01X398199Y822500D02*
X394036Y826663D01*
G01X400951Y821299D02*
X397701D01*
G01X400750Y822500D02*
X398199D01*
G01X394036Y826663D02*
X390382D01*
G01X393538Y825462D02*
X390382D01*
G01X398199Y822500D02*
X394036Y826663D01*
G01X397701Y821299D02*
X393538Y825462D01*
G01X400750Y822500D02*
X398199D01*
G01X400951Y821299D02*
X397701D01*
G01X337320Y828630D02*
X348954D01*
G01X337279Y827429D02*
X348954D01*
G01X337279D02*
X348954D01*
G01X337320Y828630D02*
X348954D01*
G01X370899Y791598D02*
X367799Y788498D01*
G01X372100Y791100D02*
X369000Y788000D01*
G01X370899Y792851D02*
Y791598D01*
G01X372100Y792850D02*
Y791100D01*
G01D02*
X369000Y788000D01*
G01X370899Y791598D02*
X367799Y788498D01*
G01X372100Y792850D02*
Y791100D01*
G01X370899Y792851D02*
Y791598D01*
G01X385899Y790601D02*
X390500Y786000D01*
G01X387100Y791099D02*
X391701Y786498D01*
G01X385899Y792851D02*
Y790601D01*
G01X387100Y792850D02*
Y791099D01*
G01D02*
X391701Y786498D01*
G01X385899Y790601D02*
X390500Y786000D01*
G01X387100Y792850D02*
Y791099D01*
G01X385899Y792851D02*
Y790601D01*
G01X337320Y828630D02*
X348954D01*
G01X337279Y827429D02*
X348954D01*
G01X337320Y828630D02*
X348954D01*
G01X337279Y827429D02*
X348954D01*
G01X337279D02*
X348954D01*
G01X337320Y828630D02*
X348954D01*
G01X337279Y827429D02*
X348954D01*
G01X337320Y828630D02*
X348954D01*
G01X337320D02*
X348954D01*
G01X337279Y827429D02*
X348954D01*
G01X337279D02*
X348954D01*
G01X337320Y828630D02*
X348954D01*
G01X393600Y858401D02*
Y860850D01*
G01X392399Y858899D02*
Y860851D01*
G01X390699Y855500D02*
X393600Y858401D01*
G01X390201Y856701D02*
X392399Y858899D01*
G01X387000Y855500D02*
X390699D01*
G01X386502Y856701D02*
X390201D01*
G01X382410Y850910D02*
X387000Y855500D01*
G01X381209Y851408D02*
X386502Y856701D01*
G01X382410Y850385D02*
Y850910D01*
G01X381209Y850500D02*
Y851408D01*
G01X392399Y858899D02*
Y860851D01*
G01X393600Y858401D02*
Y860850D01*
G01X390201Y856701D02*
X392399Y858899D01*
G01X390699Y855500D02*
X393600Y858401D01*
G01X386502Y856701D02*
X390201D01*
G01X387000Y855500D02*
X390699D01*
G01X381209Y851408D02*
X386502Y856701D01*
G01X382410Y850910D02*
X387000Y855500D01*
G01X381209Y850500D02*
Y851408D01*
G01X382410Y850385D02*
Y850910D01*
G01X378600Y856600D02*
Y860850D01*
G01X377399Y857098D02*
Y860851D01*
G01X374538Y852538D02*
X378600Y856600D01*
G01X373337Y853036D02*
X377399Y857098D01*
G01X374538Y850382D02*
Y852538D01*
G01X373337Y850500D02*
Y853036D01*
G01X377399Y857098D02*
Y860851D01*
G01X378600Y856600D02*
Y860850D01*
G01X373337Y853036D02*
X377399Y857098D01*
G01X374538Y852538D02*
X378600Y856600D01*
G01X373337Y850500D02*
Y853036D01*
G01X374538Y850382D02*
Y852538D01*
G01X358100Y858099D02*
Y860850D01*
G01X356899Y857601D02*
Y860851D01*
G01X364695Y851504D02*
X358100Y858099D01*
G01X360799Y853700D02*
X356899Y857601D01*
G01X363494Y851006D02*
X360799Y853700D01*
G01X364695Y850500D02*
Y851504D01*
G01X363494Y850384D02*
Y851006D01*
G01X356899Y857601D02*
Y860851D01*
G01X358100Y858099D02*
Y860850D01*
G01X360799Y853700D02*
X356899Y857601D01*
G01X364695Y851504D02*
X358100Y858099D01*
G01X363494Y851006D02*
X360799Y853700D01*
G01X364695Y851504D02*
X358100Y858099D01*
G01X363494Y850384D02*
Y851006D01*
G01X364695Y850500D02*
Y851504D01*
G01X343100Y859599D02*
Y860850D01*
G01X341899Y861201D02*
Y859101D01*
G01X343898Y858801D02*
X343100Y859599D01*
G01X341899Y859101D02*
X343400Y857600D01*
G01X349799Y858801D02*
X343898D01*
G01X343400Y857600D02*
X349301D01*
G01X356700Y851900D02*
X349799Y858801D01*
G01X352931Y853970D02*
X355499Y851402D01*
G01X349301Y857600D02*
X350760Y856141D01*
G01X356700Y850700D02*
Y851900D01*
G01X355499Y851402D02*
Y850600D01*
G01Y851402D02*
Y850600D01*
G01X356700Y850700D02*
Y851900D01*
G01X352931Y853970D02*
X355499Y851402D01*
G01X356700Y851900D02*
X349799Y858801D01*
G01X349301Y857600D02*
X350760Y856141D01*
G01X356700Y851900D02*
X349799Y858801D01*
G01X343400Y857600D02*
X349301D01*
G01X349799Y858801D02*
X343898D01*
G01X341899Y859101D02*
X343400Y857600D01*
G01X343898Y858801D02*
X343100Y859599D01*
G01X341899Y861201D02*
Y859101D01*
G01X343100Y859599D02*
Y860850D01*
G01X396701Y895799D02*
X333984Y958516D01*
G01X395500Y895301D02*
X333486Y957315D01*
G01X396701Y871502D02*
Y895799D01*
G01X395500Y872000D02*
Y895301D01*
G01X393500Y868301D02*
X396701Y871502D01*
G01X392299Y868799D02*
X395500Y872000D01*
G01X393500Y867250D02*
Y868301D01*
G01X392299Y867049D02*
Y868799D01*
G01X395500Y895301D02*
X333486Y957315D01*
G01X396701Y895799D02*
X333984Y958516D01*
G01X395500Y872000D02*
Y895301D01*
G01X396701Y871502D02*
Y895799D01*
G01X392299Y868799D02*
X395500Y872000D01*
G01X393500Y868301D02*
X396701Y871502D01*
G01X392299Y867049D02*
Y868799D01*
G01X393500Y867250D02*
Y868301D01*
G01X396701Y895799D02*
X333984Y958516D01*
G01X395500Y895301D02*
X333486Y957315D01*
G01X396701Y871502D02*
Y895799D01*
G01X395500Y872000D02*
Y895301D01*
G01X393500Y868301D02*
X396701Y871502D01*
G01X392299Y868799D02*
X395500Y872000D01*
G01X393500Y867250D02*
Y868301D01*
G01X392299Y867049D02*
Y868799D01*
G01X395500Y895301D02*
X333486Y957315D01*
G01X396701Y895799D02*
X333984Y958516D01*
G01X395500Y872000D02*
Y895301D01*
G01X396701Y871502D02*
Y895799D01*
G01X392299Y868799D02*
X395500Y872000D01*
G01X393500Y868301D02*
X396701Y871502D01*
G01X392299Y867049D02*
Y868799D01*
G01X393500Y867250D02*
Y868301D01*
G01X374000Y874000D02*
Y892000D01*
G01X372799Y873502D02*
Y891502D01*
G01X378700Y869300D02*
X374000Y874000D01*
G01X377499Y868802D02*
X372799Y873502D01*
G01X378700Y867050D02*
Y869300D01*
G01X377499Y867249D02*
Y868802D01*
G01X372799Y873502D02*
Y891502D01*
G01X374000Y874000D02*
Y892000D01*
G01X377499Y868802D02*
X372799Y873502D01*
G01X378700Y869300D02*
X374000Y874000D01*
G01X377499Y867249D02*
Y868802D01*
G01X378700Y867050D02*
Y869300D01*
G01X358101Y868402D02*
Y867149D01*
G01X356900Y868900D02*
Y867150D01*
G01X361201Y871502D02*
X358101Y868402D01*
G01X360000Y872000D02*
X356900Y868900D01*
G01X361201Y895799D02*
Y871502D01*
G01X360000Y895301D02*
Y872000D01*
G01X356900Y868900D02*
Y867150D01*
G01X358101Y868402D02*
Y867149D01*
G01X360000Y872000D02*
X356900Y868900D01*
G01X361201Y871502D02*
X358101Y868402D01*
G01X360000Y895301D02*
Y872000D01*
G01X361201Y895799D02*
Y871502D01*
G01X358101Y868402D02*
Y867149D01*
G01X356900Y868900D02*
Y867150D01*
G01X361201Y871502D02*
X358101Y868402D01*
G01X360000Y872000D02*
X356900Y868900D01*
G01X361201Y895799D02*
Y871502D01*
G01X360000Y895301D02*
Y872000D01*
G01X356900Y868900D02*
Y867150D01*
G01X358101Y868402D02*
Y867149D01*
G01X360000Y872000D02*
X356900Y868900D01*
G01X361201Y871502D02*
X358101Y868402D01*
G01X360000Y895301D02*
Y872000D01*
G01X361201Y895799D02*
Y871502D01*
G01X338500Y874300D02*
Y898860D01*
G01X337299Y873802D02*
Y898362D01*
G01X343000Y869800D02*
X338500Y874300D01*
G01X341799Y869302D02*
X337299Y873802D01*
G01X343000Y867250D02*
Y869800D01*
G01X341799Y867049D02*
Y869302D01*
G01X337299Y873802D02*
Y898362D01*
G01X338500Y874300D02*
Y898860D01*
G01X341799Y869302D02*
X337299Y873802D01*
G01X343000Y869800D02*
X338500Y874300D01*
G01X341799Y867049D02*
Y869302D01*
G01X343000Y867250D02*
Y869800D01*
G01X374299Y1116702D02*
X489401Y1001600D01*
G01X375500Y1117200D02*
X489899Y1002801D01*
G01X374299Y1159998D02*
Y1116702D01*
G01X375500Y1159500D02*
Y1117200D01*
G01D02*
X489899Y1002801D01*
G01X374299Y1116702D02*
X489401Y1001600D01*
G01X375500Y1159500D02*
Y1117200D01*
G01X374299Y1159998D02*
Y1116702D01*
G01D02*
X489401Y1001600D01*
G01X375500Y1117200D02*
X489899Y1002801D01*
G01X374299Y1159998D02*
Y1116702D01*
G01X375500Y1159500D02*
Y1117200D01*
G01D02*
X489899Y1002801D01*
G01X374299Y1116702D02*
X489401Y1001600D01*
G01X375500Y1159500D02*
Y1117200D01*
G01X374299Y1159998D02*
Y1116702D01*
G01X397000Y1111801D02*
X491331Y1017470D01*
G01X398201Y1112299D02*
X491829Y1018671D01*
G01X397000Y1157500D02*
Y1111801D01*
G01X398201Y1157998D02*
Y1112299D01*
G01D02*
X491829Y1018671D01*
G01X397000Y1111801D02*
X491331Y1017470D01*
G01X398201Y1157998D02*
Y1112299D01*
G01X397000Y1157500D02*
Y1111801D01*
G01X377399Y1163098D02*
X374299Y1159998D01*
G01X378600Y1162600D02*
X375500Y1159500D01*
G01X377399Y1164351D02*
Y1163098D01*
G01X378600Y1164350D02*
Y1162600D01*
G01D02*
X375500Y1159500D01*
G01X377399Y1163098D02*
X374299Y1159998D01*
G01X378600Y1164350D02*
Y1162600D01*
G01X377399Y1164351D02*
Y1163098D01*
G01Y1175101D02*
Y1170649D01*
G01X378600Y1170650D02*
Y1175599D01*
G01X373337Y1179163D02*
X377399Y1175101D01*
G01X378600Y1175599D02*
X374538Y1179661D01*
G01X373337Y1180454D02*
Y1179163D01*
G01X374538Y1179661D02*
Y1180454D01*
G01Y1179661D02*
Y1180454D01*
G01X373337D02*
Y1179163D01*
G01X378600Y1175599D02*
X374538Y1179661D01*
G01X373337Y1179163D02*
X377399Y1175101D01*
G01X378600Y1170650D02*
Y1175599D01*
G01X377399Y1175101D02*
Y1170649D01*
G01X392399Y1173031D02*
Y1170649D01*
G01X393600Y1173529D02*
Y1170650D01*
G01X390931Y1174499D02*
X392399Y1173031D01*
G01X391429Y1175700D02*
X393600Y1173529D01*
G01X385802Y1174499D02*
X390931D01*
G01X386300Y1175700D02*
X391429D01*
G01X381209Y1179092D02*
X385802Y1174499D01*
G01X382410Y1179590D02*
X386300Y1175700D01*
G01X381209Y1180454D02*
Y1179092D01*
G01X382410Y1180454D02*
Y1179590D01*
G01X393600Y1173529D02*
Y1170650D01*
G01X392399Y1173031D02*
Y1170649D01*
G01X391429Y1175700D02*
X393600Y1173529D01*
G01X390931Y1174499D02*
X392399Y1173031D01*
G01X386300Y1175700D02*
X391429D01*
G01X385802Y1174499D02*
X390931D01*
G01X382410Y1179590D02*
X386300Y1175700D01*
G01X381209Y1179092D02*
X385802Y1174499D01*
G01X382410Y1180454D02*
Y1179590D01*
G01X381209Y1180454D02*
Y1179092D01*
G01X398098Y1208899D02*
X400851D01*
G01X397600Y1210100D02*
X400850D01*
G01X394036Y1204837D02*
X398098Y1208899D01*
G01X393538Y1206038D02*
X397600Y1210100D01*
G01X393537Y1204837D02*
X394036D01*
G01X391046Y1206038D02*
X393538D01*
G01X392539Y1204834D02*
X393534D01*
G01X391046Y1206038D02*
X393538D01*
G01X391046Y1204837D02*
X392536D01*
G01X391046Y1206038D02*
X393538D01*
G01X397600Y1210100D02*
X400850D01*
G01X398098Y1208899D02*
X400851D01*
G01X393538Y1206038D02*
X397600Y1210100D01*
G01X394036Y1204837D02*
X398098Y1208899D01*
G01X391046Y1206038D02*
X393538D01*
G01X393537Y1204837D02*
X394036D01*
G01X392539Y1204834D02*
X393534D01*
G01X391046Y1204837D02*
X392536D01*
G01X338020Y1200130D02*
X348954D01*
G01X337979Y1198929D02*
X348954D01*
G01X337979D02*
X348954D01*
G01X338020Y1200130D02*
X348954D01*
G01X377399Y1163098D02*
X374299Y1159998D01*
G01X378600Y1162600D02*
X375500Y1159500D01*
G01X377399Y1164351D02*
Y1163098D01*
G01X378600Y1164350D02*
Y1162600D01*
G01D02*
X375500Y1159500D01*
G01X377399Y1163098D02*
X374299Y1159998D01*
G01X378600Y1164350D02*
Y1162600D01*
G01X377399Y1164351D02*
Y1163098D01*
G01X392399Y1162101D02*
X397000Y1157500D01*
G01X393600Y1162599D02*
X398201Y1157998D01*
G01X392399Y1164351D02*
Y1162101D01*
G01X393600Y1164350D02*
Y1162599D01*
G01D02*
X398201Y1157998D01*
G01X392399Y1162101D02*
X397000Y1157500D01*
G01X393600Y1164350D02*
Y1162599D01*
G01X392399Y1164351D02*
Y1162101D01*
G01X338020Y1200130D02*
X348954D01*
G01X337979Y1198929D02*
X348954D01*
G01X338020Y1200130D02*
X348954D01*
G01X337979Y1198929D02*
X348954D01*
G01X337979D02*
X348954D01*
G01X338020Y1200130D02*
X348954D01*
G01X337979Y1198929D02*
X348954D01*
G01X338020Y1200130D02*
X348954D01*
G01X338020D02*
X348954D01*
G01X337979Y1198929D02*
X348954D01*
G01X337979D02*
X348954D01*
G01X338020Y1200130D02*
X348954D01*
G01X382410Y1223819D02*
Y1222546D01*
G01X381209D02*
Y1224317D01*
G01X385591Y1227000D02*
X382410Y1223819D01*
G01X381209Y1224317D02*
X385093Y1228201D01*
G01X390699Y1227000D02*
X385591D01*
G01X385093Y1228201D02*
X390201D01*
G01X393600Y1229901D02*
X390699Y1227000D01*
G01X390201Y1228201D02*
X392399Y1230399D01*
G01X393600Y1232350D02*
Y1229901D01*
G01X392399Y1230399D02*
Y1232351D01*
G01Y1230399D02*
Y1232351D01*
G01X393600Y1232350D02*
Y1229901D01*
G01X390201Y1228201D02*
X392399Y1230399D01*
G01X393600Y1229901D02*
X390699Y1227000D01*
G01X385093Y1228201D02*
X390201D01*
G01X390699Y1227000D02*
X385591D01*
G01X381209Y1224317D02*
X385093Y1228201D01*
G01X385591Y1227000D02*
X382410Y1223819D01*
G01X381209Y1222546D02*
Y1224317D01*
G01X382410Y1223819D02*
Y1222546D01*
G01X374538Y1224038D02*
Y1222546D01*
G01X373337Y1224536D02*
Y1222546D01*
G01X378600Y1228100D02*
X374538Y1224038D01*
G01X377399Y1228598D02*
X373337Y1224536D01*
G01X378600Y1232350D02*
Y1228100D01*
G01X377399Y1232351D02*
Y1228598D01*
G01X373337Y1224536D02*
Y1222546D01*
G01X374538Y1224038D02*
Y1222546D01*
G01X377399Y1228598D02*
X373337Y1224536D01*
G01X378600Y1228100D02*
X374538Y1224038D01*
G01X377399Y1232351D02*
Y1228598D01*
G01X378600Y1232350D02*
Y1228100D01*
G01X358100Y1229700D02*
Y1232350D01*
G01X356899Y1229202D02*
Y1232351D01*
G01X362199Y1225601D02*
X358100Y1229700D01*
G01X361701Y1224400D02*
X356899Y1229202D01*
G01X363099Y1225601D02*
X362199D01*
G01X362601Y1224400D02*
X361701D01*
G01X364696Y1224004D02*
X363099Y1225601D01*
G01X362601Y1224400D02*
X361701D01*
G01X363495Y1223506D02*
X362601Y1224400D01*
G01X364696Y1222546D02*
Y1224004D01*
G01X363495Y1222546D02*
Y1223506D01*
G01X356899Y1229202D02*
Y1232351D01*
G01X358100Y1229700D02*
Y1232350D01*
G01X361701Y1224400D02*
X356899Y1229202D01*
G01X362199Y1225601D02*
X358100Y1229700D01*
G01X362601Y1224400D02*
X361701D01*
G01X363099Y1225601D02*
X362199D01*
G01X364696Y1224004D02*
X363099Y1225601D01*
G01X363495Y1223506D02*
X362601Y1224400D01*
G01X364696Y1224004D02*
X363099Y1225601D01*
G01X363495Y1222546D02*
Y1223506D01*
G01X364696Y1222546D02*
Y1224004D01*
G01X343100Y1230900D02*
Y1232350D01*
G01X341899Y1233001D02*
Y1230402D01*
G01X344000Y1230000D02*
X343100Y1230900D01*
G01X341899Y1230402D02*
X343502Y1228799D01*
G01X348706Y1230000D02*
X344000D01*
G01X343502Y1228799D02*
X348208D01*
G01X357205Y1221491D02*
X348706Y1230000D01*
G01X353676Y1223323D02*
X355235Y1221763D01*
G01X352965Y1223324D02*
X353676Y1223323D01*
G01X348208Y1228799D02*
X351507Y1225496D01*
G01X353676Y1223323D02*
X355235Y1221763D01*
G01X357205Y1221491D02*
X348706Y1230000D01*
G01X352965Y1223324D02*
X353676Y1223323D01*
G01X357205Y1221491D02*
X348706Y1230000D01*
G01X348208Y1228799D02*
X351507Y1225496D01*
G01X357205Y1221491D02*
X348706Y1230000D01*
G01X343502Y1228799D02*
X348208D01*
G01X348706Y1230000D02*
X344000D01*
G01X341899Y1230402D02*
X343502Y1228799D01*
G01X344000Y1230000D02*
X343100Y1230900D01*
G01X341899Y1233001D02*
Y1230402D01*
G01X343100Y1230900D02*
Y1232350D01*
G01X392008Y1212710D02*
X391046D01*
G01X391510Y1213911D02*
X391046D01*
G01X397201Y1217903D02*
X392008Y1212710D01*
G01X396000Y1218401D02*
X391510Y1213911D01*
G01X397201Y1222631D02*
Y1217903D01*
G01X396000Y1223129D02*
Y1218401D01*
G01X398469Y1223899D02*
X397201Y1222631D01*
G01X397971Y1225100D02*
X396000Y1223129D01*
G01X400851Y1223899D02*
X398469D01*
G01X400850Y1225100D02*
X397971D01*
G01X391510Y1213911D02*
X391046D01*
G01X392008Y1212710D02*
X391046D01*
G01X396000Y1218401D02*
X391510Y1213911D01*
G01X397201Y1217903D02*
X392008Y1212710D01*
G01X396000Y1223129D02*
Y1218401D01*
G01X397201Y1222631D02*
Y1217903D01*
G01X397971Y1225100D02*
X396000Y1223129D01*
G01X398469Y1223899D02*
X397201Y1222631D01*
G01X400850Y1225100D02*
X397971D01*
G01X400851Y1223899D02*
X398469D01*
G01X393500Y1239801D02*
Y1238750D01*
G01X392299Y1238549D02*
Y1240299D01*
G01X396701Y1243002D02*
X393500Y1239801D01*
G01X392299Y1240299D02*
X395500Y1243500D01*
G01X396701Y1267498D02*
Y1243002D01*
G01X395500Y1243500D02*
Y1267000D01*
G01Y1243500D02*
Y1267000D01*
G01X396701Y1267498D02*
Y1243002D01*
G01X392299Y1240299D02*
X395500Y1243500D01*
G01X396701Y1243002D02*
X393500Y1239801D01*
G01X392299Y1238549D02*
Y1240299D01*
G01X393500Y1239801D02*
Y1238750D01*
G01Y1239801D02*
Y1238750D01*
G01X392299Y1238549D02*
Y1240299D01*
G01X396701Y1243002D02*
X393500Y1239801D01*
G01X392299Y1240299D02*
X395500Y1243500D01*
G01X396701Y1267498D02*
Y1243002D01*
G01X395500Y1243500D02*
Y1267000D01*
G01Y1243500D02*
Y1267000D01*
G01X396701Y1267498D02*
Y1243002D01*
G01X392299Y1240299D02*
X395500Y1243500D01*
G01X396701Y1243002D02*
X393500Y1239801D01*
G01X392299Y1238549D02*
Y1240299D01*
G01X393500Y1239801D02*
Y1238750D01*
G01X374000Y1245500D02*
Y1263699D01*
G01X372799Y1245002D02*
Y1263201D01*
G01X378700Y1240800D02*
X374000Y1245500D01*
G01X377499Y1240302D02*
X372799Y1245002D01*
G01X378700Y1238550D02*
Y1240800D01*
G01X377499Y1238749D02*
Y1240302D01*
G01X372799Y1245002D02*
Y1263201D01*
G01X374000Y1245500D02*
Y1263699D01*
G01X377499Y1240302D02*
X372799Y1245002D01*
G01X378700Y1240800D02*
X374000Y1245500D01*
G01X377499Y1238749D02*
Y1240302D01*
G01X378700Y1238550D02*
Y1240800D01*
G01X361201Y1243002D02*
Y1266998D01*
G01X360000Y1243500D02*
Y1266500D01*
G01X358101Y1239902D02*
X361201Y1243002D01*
G01X356900Y1240400D02*
X360000Y1243500D01*
G01X358101Y1238649D02*
Y1239902D01*
G01X356900Y1238650D02*
Y1240400D01*
G01X360000Y1243500D02*
Y1266500D01*
G01X361201Y1243002D02*
Y1266998D01*
G01X356900Y1240400D02*
X360000Y1243500D01*
G01X358101Y1239902D02*
X361201Y1243002D01*
G01X356900Y1238650D02*
Y1240400D01*
G01X358101Y1238649D02*
Y1239902D01*
G01X338500Y1245500D02*
Y1270000D01*
G01X337299Y1245002D02*
Y1269502D01*
G01X343101Y1240899D02*
X338500Y1245500D01*
G01X341900Y1240401D02*
X337299Y1245002D01*
G01X343101Y1238649D02*
Y1240899D01*
G01X341900Y1238650D02*
Y1240401D01*
G01X337299Y1245002D02*
Y1269502D01*
G01X338500Y1245500D02*
Y1270000D01*
G01X341900Y1240401D02*
X337299Y1245002D01*
G01X343101Y1240899D02*
X338500Y1245500D01*
G01X341900Y1238650D02*
Y1240401D01*
G01X343101Y1238649D02*
Y1240899D01*
G01X361201Y1243002D02*
Y1266998D01*
G01X360000Y1243500D02*
Y1266500D01*
G01X358101Y1239902D02*
X361201Y1243002D01*
G01X356900Y1240400D02*
X360000Y1243500D01*
G01X358101Y1238649D02*
Y1239902D01*
G01X356900Y1238650D02*
Y1240400D01*
G01X360000Y1243500D02*
Y1266500D01*
G01X361201Y1243002D02*
Y1266998D01*
G01X356900Y1240400D02*
X360000Y1243500D01*
G01X358101Y1239902D02*
X361201Y1243002D01*
G01X356900Y1238650D02*
Y1240400D01*
G01X358101Y1238649D02*
Y1239902D01*
G01X338799Y1648498D02*
X332801Y1642500D01*
G01X340000Y1648000D02*
X333299Y1641299D01*
G01X340000Y1658000D02*
Y1648000D01*
G01D02*
X333299Y1641299D01*
G01X338799Y1648498D02*
X332801Y1642500D01*
G01X340000Y1658000D02*
Y1648000D01*
G01X338799Y1648498D02*
X332801Y1642500D01*
G01X340000Y1648000D02*
X333299Y1641299D01*
G01X340000Y1658000D02*
Y1648000D01*
G01D02*
X333299Y1641299D01*
G01X338799Y1648498D02*
X332801Y1642500D01*
G01X340000Y1658000D02*
Y1648000D01*
G01X361500Y1637699D02*
X351301Y1627500D01*
G01X362701Y1637201D02*
X351799Y1626299D01*
G01X361500Y1656000D02*
Y1637699D01*
G01X362701Y1656498D02*
Y1637201D01*
G01D02*
X351799Y1626299D01*
G01X361500Y1637699D02*
X351301Y1627500D01*
G01X362701Y1656498D02*
Y1637201D01*
G01X361500Y1656000D02*
Y1637699D01*
G01X363494Y1721006D02*
X359499Y1724999D01*
G01X364695Y1720500D02*
Y1721504D01*
G01X363494Y1720384D02*
Y1721006D01*
G01D02*
X359499Y1724999D01*
G01X363494Y1720384D02*
Y1721006D01*
G01X364695Y1720500D02*
Y1721504D01*
G01X354199Y1723581D02*
X357205Y1720575D01*
G01X355235Y1720846D02*
X353701Y1722380D01*
G01X355235Y1720846D02*
X353701Y1722380D01*
G01X354199Y1723581D02*
X357205Y1720575D01*
G01X352861Y1676331D02*
X355235Y1678705D01*
G01X349729Y1671500D02*
X357205Y1678976D01*
G01X352150Y1676331D02*
X352861D01*
G01X349729Y1671500D02*
X357205Y1678976D01*
G01X349231Y1672701D02*
X350690Y1674160D01*
G01X349729Y1671500D02*
X357205Y1678976D01*
G01X344002Y1672701D02*
X349231D01*
G01X344500Y1671500D02*
X349729D01*
G01X341899Y1670598D02*
X344002Y1672701D01*
G01X343100Y1670100D02*
X344500Y1671500D01*
G01X341899Y1668399D02*
Y1670598D01*
G01X343100Y1669150D02*
Y1670100D01*
G01X349729Y1671500D02*
X357205Y1678976D01*
G01X352861Y1676331D02*
X355235Y1678705D01*
G01X352150Y1676331D02*
X352861D01*
G01X349231Y1672701D02*
X350690Y1674160D01*
G01X344500Y1671500D02*
X349729D01*
G01X344002Y1672701D02*
X349231D01*
G01X343100Y1670100D02*
X344500Y1671500D01*
G01X341899Y1670598D02*
X344002Y1672701D01*
G01X343100Y1669150D02*
Y1670100D01*
G01X341899Y1668399D02*
Y1670598D01*
G01X356899D02*
Y1669149D01*
G01X358100Y1670100D02*
Y1669150D01*
G01X363492Y1677191D02*
X356899Y1670598D01*
G01X364693Y1676693D02*
X358100Y1670100D01*
G01X363492Y1679618D02*
Y1677191D01*
G01X364693Y1679613D02*
Y1676693D01*
G01X358100Y1670100D02*
Y1669150D01*
G01X356899Y1670598D02*
Y1669149D01*
G01X364693Y1676693D02*
X358100Y1670100D01*
G01X363492Y1677191D02*
X356899Y1670598D01*
G01X364693Y1679613D02*
Y1676693D01*
G01X363492Y1679618D02*
Y1677191D01*
G01X397598Y1707399D02*
X400851D01*
G01X397100Y1708600D02*
X400850D01*
G01X393534Y1703335D02*
X397598Y1707399D01*
G01X393036Y1704536D02*
X397100Y1708600D01*
G01X390880Y1703335D02*
X393534D01*
G01X390884Y1704536D02*
X393036D01*
G01X397100Y1708600D02*
X400850D01*
G01X397598Y1707399D02*
X400851D01*
G01X393036Y1704536D02*
X397100Y1708600D01*
G01X393534Y1703335D02*
X397598Y1707399D01*
G01X390884Y1704536D02*
X393036D01*
G01X390880Y1703335D02*
X393534D01*
G01X397201Y1721131D02*
X398469Y1722399D01*
G01X397201Y1716179D02*
Y1721131D01*
G01X396000Y1716677D02*
Y1721629D01*
G01X392232Y1711210D02*
X397201Y1716179D01*
G01X391734Y1712411D02*
X396000Y1716677D01*
G01X391046Y1711210D02*
X392232D01*
G01X391046Y1712411D02*
X391734D01*
G01X397201Y1721131D02*
X398469Y1722399D01*
G01X396000Y1716677D02*
Y1721629D01*
G01X397201Y1716179D02*
Y1721131D01*
G01X391734Y1712411D02*
X396000Y1716677D01*
G01X392232Y1711210D02*
X397201Y1716179D01*
G01X391046Y1712411D02*
X391734D01*
G01X391046Y1711210D02*
X392232D01*
G01X338799Y1658498D02*
Y1648498D01*
G01X341699Y1661398D02*
X338799Y1658498D01*
G01X342900Y1660900D02*
X340000Y1658000D01*
G01X341699Y1663051D02*
Y1661398D01*
G01X342900Y1662650D02*
Y1660900D01*
G01X338799Y1658498D02*
Y1648498D01*
G01X342900Y1660900D02*
X340000Y1658000D01*
G01X341699Y1661398D02*
X338799Y1658498D01*
G01X342900Y1662650D02*
Y1660900D01*
G01X341699Y1663051D02*
Y1661398D01*
G01X338799Y1658498D02*
Y1648498D01*
G01X341699Y1661398D02*
X338799Y1658498D01*
G01X342900Y1660900D02*
X340000Y1658000D01*
G01X341699Y1663051D02*
Y1661398D01*
G01X342900Y1662650D02*
Y1660900D01*
G01X338799Y1658498D02*
Y1648498D01*
G01X342900Y1660900D02*
X340000Y1658000D01*
G01X341699Y1661398D02*
X338799Y1658498D01*
G01X342900Y1662650D02*
Y1660900D01*
G01X341699Y1663051D02*
Y1661398D01*
G01X356899Y1660601D02*
X361500Y1656000D01*
G01X358100Y1661099D02*
X362701Y1656498D01*
G01X356899Y1662851D02*
Y1660601D01*
G01X358100Y1662850D02*
Y1661099D01*
G01D02*
X362701Y1656498D01*
G01X356899Y1660601D02*
X361500Y1656000D01*
G01X358100Y1662850D02*
Y1661099D01*
G01X356899Y1662851D02*
Y1660601D01*
G01X358100Y1728099D02*
Y1730850D01*
G01X356899Y1727601D02*
Y1730851D01*
G01X360349Y1725849D02*
X358100Y1728099D01*
G01X358374Y1726124D02*
X356899Y1727601D01*
G01X359499Y1724999D02*
X358374Y1726124D01*
G01X364695Y1721504D02*
X360349Y1725849D01*
G01X356899Y1727601D02*
Y1730851D01*
G01X358100Y1728099D02*
Y1730850D01*
G01X358374Y1726124D02*
X356899Y1727601D01*
G01X360349Y1725849D02*
X358100Y1728099D01*
G01X359499Y1724999D02*
X358374Y1726124D01*
G01X360349Y1725849D02*
X358100Y1728099D01*
G01X364695Y1721504D02*
X360349Y1725849D01*
G01X349618Y1723581D02*
X354199D01*
G01X353701Y1722380D02*
X349120D01*
G01X343201Y1729998D02*
X349618Y1723581D01*
G01X343459Y1728041D02*
X342000Y1729500D01*
G01X345630Y1725870D02*
X344919D01*
G01X349120Y1722380D02*
X345630Y1725870D01*
G01X343201Y1730951D02*
Y1729998D01*
G01X342000Y1729500D02*
Y1731300D01*
G01Y1729500D02*
Y1731300D01*
G01X343201Y1730951D02*
Y1729998D01*
G01X343459Y1728041D02*
X342000Y1729500D01*
G01X343201Y1729998D02*
X349618Y1723581D01*
G01X345630Y1725870D02*
X344919D01*
G01X343201Y1729998D02*
X349618Y1723581D01*
G01X349120Y1722380D02*
X345630Y1725870D01*
G01X343201Y1729998D02*
X349618Y1723581D01*
G01X353701Y1722380D02*
X349120D01*
G01X349618Y1723581D02*
X354199D01*
G01X398469Y1722399D02*
X400851D01*
G01X397971Y1723600D02*
X400850D01*
G01X396000Y1721629D02*
X397971Y1723600D01*
G01D02*
X400850D01*
G01X398469Y1722399D02*
X400851D01*
G01X396000Y1721629D02*
X397971Y1723600D01*
G01X361201Y1741502D02*
Y1786998D01*
G01X360000Y1742000D02*
Y1786500D01*
G01X358101Y1738402D02*
X361201Y1741502D01*
G01X356900Y1738900D02*
X360000Y1742000D01*
G01X358101Y1737149D02*
Y1738402D01*
G01X356900Y1737150D02*
Y1738900D01*
G01X360000Y1742000D02*
Y1786500D01*
G01X361201Y1741502D02*
Y1786998D01*
G01X356900Y1738900D02*
X360000Y1742000D01*
G01X358101Y1738402D02*
X361201Y1741502D01*
G01X356900Y1737150D02*
Y1738900D01*
G01X358101Y1737149D02*
Y1738402D01*
G01X361201Y1741502D02*
Y1786998D01*
G01X360000Y1742000D02*
Y1786500D01*
G01X358101Y1738402D02*
X361201Y1741502D01*
G01X356900Y1738900D02*
X360000Y1742000D01*
G01X358101Y1737149D02*
Y1738402D01*
G01X356900Y1737150D02*
Y1738900D01*
G01X360000Y1742000D02*
Y1786500D01*
G01X361201Y1741502D02*
Y1786998D01*
G01X356900Y1738900D02*
X360000Y1742000D01*
G01X358101Y1738402D02*
X361201Y1741502D01*
G01X356900Y1737150D02*
Y1738900D01*
G01X358101Y1737149D02*
Y1738402D01*
G01X338500Y1744000D02*
Y1786000D01*
G01X337299Y1785502D02*
Y1743502D01*
G01X343101Y1739399D02*
X338500Y1744000D01*
G01X337299Y1743502D02*
X341900Y1738901D01*
G01X343101Y1737149D02*
Y1739399D01*
G01X341900Y1738901D02*
Y1737150D01*
G01Y1738901D02*
Y1737150D01*
G01X343101Y1737149D02*
Y1739399D01*
G01X337299Y1743502D02*
X341900Y1738901D01*
G01X343101Y1739399D02*
X338500Y1744000D01*
G01X337299Y1785502D02*
Y1743502D01*
G01X338500Y1744000D02*
Y1786000D01*
G01X436000Y642444D02*
X488645Y589799D01*
G01X437201Y642942D02*
X489143Y591000D01*
G01X437201Y642942D02*
X489143Y591000D01*
G01X436000Y642444D02*
X488645Y589799D01*
G01X453500Y649694D02*
X491236Y611958D01*
G01X436000Y642444D02*
X488645Y589799D01*
G01X437201Y642942D02*
X489143Y591000D01*
G01X437201Y642942D02*
X489143Y591000D01*
G01X436000Y642444D02*
X488645Y589799D01*
G01X453500Y649694D02*
X491236Y611958D01*
G01X436000Y797500D02*
Y642444D01*
G01X437201Y797998D02*
Y642942D01*
G01Y797998D02*
Y642942D01*
G01X436000Y797500D02*
Y642444D01*
G01X454701Y650192D02*
X491734Y613159D01*
G01X454701Y817498D02*
Y650192D01*
G01X453500Y817000D02*
Y649694D01*
G01X436000Y797500D02*
Y642444D01*
G01X437201Y797998D02*
Y642942D01*
G01Y797998D02*
Y642942D01*
G01X436000Y797500D02*
Y642444D01*
G01X454701Y650192D02*
X491734Y613159D01*
G01X453500Y817000D02*
Y649694D01*
G01X454701Y817498D02*
Y650192D01*
G01X430201Y803299D02*
X436000Y797500D01*
G01X430699Y804500D02*
X437201Y797998D01*
G01X411802Y803299D02*
X430201D01*
G01X412300Y804500D02*
X430699D01*
G01X408902Y806199D02*
X411802Y803299D01*
G01X409400Y807400D02*
X412300Y804500D01*
G01X406949Y806199D02*
X408902D01*
G01X407350Y807400D02*
X409400D01*
G01X430699Y804500D02*
X437201Y797998D01*
G01X430201Y803299D02*
X436000Y797500D01*
G01X412300Y804500D02*
X430699D01*
G01X411802Y803299D02*
X430201D01*
G01X409400Y807400D02*
X412300Y804500D01*
G01X408902Y806199D02*
X411802Y803299D01*
G01X407350Y807400D02*
X409400D01*
G01X406949Y806199D02*
X408902D01*
G01X444998Y827201D02*
X454701Y817498D01*
G01X444500Y826000D02*
X453500Y817000D01*
G01X413502Y827201D02*
X444998D01*
G01X414000Y826000D02*
X444500D01*
G01X408901Y822600D02*
X413502Y827201D01*
G01X409399Y821399D02*
X414000Y826000D01*
G01X407150Y822600D02*
X408901D01*
G01X407149Y821399D02*
X409399D01*
G01X430201Y803299D02*
X436000Y797500D01*
G01X430699Y804500D02*
X437201Y797998D01*
G01X411802Y803299D02*
X430201D01*
G01X412300Y804500D02*
X430699D01*
G01X408902Y806199D02*
X411802Y803299D01*
G01X409400Y807400D02*
X412300Y804500D01*
G01X406949Y806199D02*
X408902D01*
G01X407350Y807400D02*
X409400D01*
G01X430699Y804500D02*
X437201Y797998D01*
G01X430201Y803299D02*
X436000Y797500D01*
G01X412300Y804500D02*
X430699D01*
G01X411802Y803299D02*
X430201D01*
G01X409400Y807400D02*
X412300Y804500D01*
G01X408902Y806199D02*
X411802Y803299D01*
G01X407350Y807400D02*
X409400D01*
G01X406949Y806199D02*
X408902D01*
G01X444500Y826000D02*
X453500Y817000D01*
G01X444998Y827201D02*
X454701Y817498D01*
G01X414000Y826000D02*
X444500D01*
G01X413502Y827201D02*
X444998D01*
G01X409399Y821399D02*
X414000Y826000D01*
G01X408901Y822600D02*
X413502Y827201D01*
G01X407149Y821399D02*
X409399D01*
G01X407150Y822600D02*
X408901D01*
G01X408602Y1208999D02*
X407249D01*
G01X409100Y1210200D02*
X407050D01*
G01X412601Y1205000D02*
X408602Y1208999D01*
G01X413099Y1206201D02*
X409100Y1210200D01*
G01X508699Y1205000D02*
X412601D01*
G01X508201Y1206201D02*
X413099D01*
G01X409100Y1210200D02*
X407050D01*
G01X408602Y1208999D02*
X407249D01*
G01X413099Y1206201D02*
X409100Y1210200D01*
G01X412601Y1205000D02*
X408602Y1208999D01*
G01X508201Y1206201D02*
X413099D01*
G01X508699Y1205000D02*
X412601D01*
G01X408602Y1208999D02*
X407249D01*
G01X409100Y1210200D02*
X407050D01*
G01X412601Y1205000D02*
X408602Y1208999D01*
G01X413099Y1206201D02*
X409100Y1210200D01*
G01X508699Y1205000D02*
X412601D01*
G01X508201Y1206201D02*
X413099D01*
G01X409100Y1210200D02*
X407050D01*
G01X408602Y1208999D02*
X407249D01*
G01X413099Y1206201D02*
X409100Y1210200D01*
G01X412601Y1205000D02*
X408602Y1208999D01*
G01X508201Y1206201D02*
X413099D01*
G01X508699Y1205000D02*
X412601D01*
G01X409400Y1223900D02*
X407150D01*
G01X408902Y1225101D02*
X407149D01*
G01X414000Y1228500D02*
X409400Y1223900D01*
G01X413502Y1229701D02*
X408902Y1225101D01*
G01X507500Y1228500D02*
X414000D01*
G01X507002Y1229701D02*
X413502D01*
G01X408902Y1225101D02*
X407149D01*
G01X409400Y1223900D02*
X407150D01*
G01X413502Y1229701D02*
X408902Y1225101D01*
G01X414000Y1228500D02*
X409400Y1223900D01*
G01X507002Y1229701D02*
X413502D01*
G01X507500Y1228500D02*
X414000D01*
G01X451613Y1710280D02*
X705979D01*
G01X451115Y1711481D02*
X705481D01*
G01X445632Y1704299D02*
X451613Y1710280D01*
G01X445134Y1705500D02*
X451115Y1711481D01*
G01X411902Y1704299D02*
X445632D01*
G01X412400Y1705500D02*
X445134D01*
G01X409002Y1707199D02*
X411902Y1704299D01*
G01X409500Y1708400D02*
X412400Y1705500D01*
G01X406949Y1707199D02*
X409002D01*
G01X407350Y1708400D02*
X409500D01*
G01X451115Y1711481D02*
X705481D01*
G01X451613Y1710280D02*
X705979D01*
G01X445134Y1705500D02*
X451115Y1711481D01*
G01X445632Y1704299D02*
X451613Y1710280D01*
G01X412400Y1705500D02*
X445134D01*
G01X411902Y1704299D02*
X445632D01*
G01X409500Y1708400D02*
X412400Y1705500D01*
G01X409002Y1707199D02*
X411902Y1704299D01*
G01X407350Y1708400D02*
X409500D01*
G01X406949Y1707199D02*
X409002D01*
G01X451613Y1710280D02*
X705979D01*
G01X451115Y1711481D02*
X705481D01*
G01X445632Y1704299D02*
X451613Y1710280D01*
G01X445134Y1705500D02*
X451115Y1711481D01*
G01X411902Y1704299D02*
X445632D01*
G01X412400Y1705500D02*
X445134D01*
G01X409002Y1707199D02*
X411902Y1704299D01*
G01X409500Y1708400D02*
X412400Y1705500D01*
G01X406949Y1707199D02*
X409002D01*
G01X407350Y1708400D02*
X409500D01*
G01X451115Y1711481D02*
X705481D01*
G01X451613Y1710280D02*
X705979D01*
G01X445134Y1705500D02*
X451115Y1711481D01*
G01X445632Y1704299D02*
X451613Y1710280D01*
G01X412400Y1705500D02*
X445134D01*
G01X411902Y1704299D02*
X445632D01*
G01X409500Y1708400D02*
X412400Y1705500D01*
G01X409002Y1707199D02*
X411902Y1704299D01*
G01X407350Y1708400D02*
X409500D01*
G01X406949Y1707199D02*
X409002D01*
G01X408901Y1723600D02*
X407150D01*
G01X409399Y1722399D02*
X407149D01*
G01X414000Y1727000D02*
X409399Y1722399D01*
G01X413502Y1728201D02*
X408901Y1723600D01*
G01X414000Y1727000D02*
X409399Y1722399D01*
G01X704201Y1728201D02*
X413502D01*
G01X704699Y1727000D02*
X414000D01*
G01X409399Y1722399D02*
X407149D01*
G01X408901Y1723600D02*
X407150D01*
G01X414000Y1727000D02*
X409399Y1722399D01*
G01X408901Y1723600D02*
X407150D01*
G01X413502Y1728201D02*
X408901Y1723600D01*
G01X704699Y1727000D02*
X414000D01*
G01X704201Y1728201D02*
X413502D01*
G01X488645Y589799D02*
X894018D01*
G01X489143Y591000D02*
X877918D01*
G01X488645Y589799D02*
X894018D01*
G01X488645D02*
X894018D01*
G01X489143Y591000D02*
X877918D01*
G01X488645Y589799D02*
X894018D01*
G01X491734Y613159D02*
X877159D01*
G01X491236Y611958D02*
X877000D01*
G01X488645Y589799D02*
X894018D01*
G01X489143Y591000D02*
X877918D01*
G01X488645Y589799D02*
X894018D01*
G01X488645D02*
X894018D01*
G01X489143Y591000D02*
X877918D01*
G01X488645Y589799D02*
X894018D01*
G01X491236Y611958D02*
X877000D01*
G01X491734Y613159D02*
X877159D01*
G01X489401Y1001600D02*
X867701D01*
G01X489899Y1002801D02*
X812909D01*
G01X489401Y1001600D02*
X867701D01*
G01X489401D02*
X867701D01*
G01X489401D02*
X867701D01*
G01X489401D02*
X867701D01*
G01X489401D02*
X867701D01*
G01X489401D02*
X867701D01*
G01X489401D02*
X867701D01*
G01X489401D02*
X867701D01*
G01X489899Y1002801D02*
X812909D01*
G01X489401Y1001600D02*
X867701D01*
G01X489401D02*
X867701D01*
G01X489899Y1002801D02*
X812909D01*
G01X489401Y1001600D02*
X867701D01*
G01X489401D02*
X867701D01*
G01X489401D02*
X867701D01*
G01X489401D02*
X867701D01*
G01X489401D02*
X867701D01*
G01X489401D02*
X867701D01*
G01X489401D02*
X867701D01*
G01X489401D02*
X867701D01*
G01X489899Y1002801D02*
X812909D01*
G01X489401Y1001600D02*
X867701D01*
G01X491331Y1017470D02*
X877500D01*
G01X491829Y1018671D02*
X840259D01*
G01X491331Y1017470D02*
X877500D01*
G01X491331D02*
X877500D01*
G01X491331D02*
X877500D01*
G01X491331D02*
X877500D01*
G01X491331D02*
X877500D01*
G01X491829Y1018671D02*
X840259D01*
G01X491331Y1017470D02*
X877500D01*
G01X704998Y1401299D02*
X508699Y1205000D01*
G01X704500Y1402500D02*
X508201Y1206201D01*
G01X704500Y1402500D02*
X508201Y1206201D01*
G01X704998Y1401299D02*
X508699Y1205000D01*
G01X704998Y1401299D02*
X508699Y1205000D01*
G01X704500Y1402500D02*
X508201Y1206201D01*
G01X704500Y1402500D02*
X508201Y1206201D01*
G01X704998Y1401299D02*
X508699Y1205000D01*
G01X701982Y1422982D02*
X507500Y1228500D01*
G01X701484Y1424183D02*
X507002Y1229701D01*
G01X701484Y1424183D02*
X507002Y1229701D01*
G01X701982Y1422982D02*
X507500Y1228500D01*
G01X903799Y1401299D02*
X704998D01*
G01X804868Y1402500D02*
X704500D01*
G01X804868D02*
X704500D01*
G01X903799Y1401299D02*
X704998D01*
G01X903799D02*
X704998D01*
G01X903799D02*
X704998D01*
G01X903799D02*
X704998D01*
G01X903799D02*
X704998D01*
G01X903799D02*
X704998D01*
G01X903799D02*
X704998D01*
G01X903799D02*
X704998D01*
G01X903799D02*
X704998D01*
G01X903799D02*
X704998D01*
G01X903799D02*
X704998D01*
G01X877526Y1422982D02*
X701982D01*
G01X877500Y1424183D02*
X701484D01*
G01X877500D02*
X701484D01*
G01X877526Y1422982D02*
X701982D01*
G01X903799Y1401299D02*
X704998D01*
G01X804868Y1402500D02*
X704500D01*
G01X804868D02*
X704500D01*
G01X903799Y1401299D02*
X704998D01*
G01X903799D02*
X704998D01*
G01X903799D02*
X704998D01*
G01X903799D02*
X704998D01*
G01X903799D02*
X704998D01*
G01X903799D02*
X704998D01*
G01X903799D02*
X704998D01*
G01X903799D02*
X704998D01*
G01X903799D02*
X704998D01*
G01X903799D02*
X704998D01*
G01X903799D02*
X704998D01*
G01X705979Y1710280D02*
X758498Y1762799D01*
G01X705481Y1711481D02*
X747109Y1753109D01*
G01X705979Y1710280D02*
X758498Y1762799D01*
G01X705979Y1710280D02*
X758498Y1762799D01*
G01X705979Y1710280D02*
X758498Y1762799D01*
G01X705481Y1711481D02*
X747109Y1753109D01*
G01X705979Y1710280D02*
X758498Y1762799D01*
G01X705979Y1710280D02*
X758498Y1762799D01*
G01X705481Y1711481D02*
X747109Y1753109D01*
G01X705979Y1710280D02*
X758498Y1762799D01*
G01X705979Y1710280D02*
X758498Y1762799D01*
G01X705979Y1710280D02*
X758498Y1762799D01*
G01X705481Y1711481D02*
X747109Y1753109D01*
G01X705979Y1710280D02*
X758498Y1762799D01*
G01D02*
X847998D01*
G01X758000Y1764000D02*
X847500D01*
G01X756541Y1762541D02*
X758000Y1764000D01*
G01X752910Y1758910D02*
X754370Y1760370D01*
G01X749280Y1755280D02*
X750739Y1756739D01*
G01X758000Y1764000D02*
X847500D01*
G01X758498Y1762799D02*
X847998D01*
G01X756541Y1762541D02*
X758000Y1764000D01*
G01X752910Y1758910D02*
X754370Y1760370D01*
G01X749280Y1755280D02*
X750739Y1756739D01*
G01X752701Y1776701D02*
X704201Y1728201D01*
G01X753199Y1775500D02*
X704699Y1727000D01*
G01X840201Y1776701D02*
X752701D01*
G01X840699Y1775500D02*
X753199D01*
G01X758498Y1762799D02*
X847998D01*
G01X758000Y1764000D02*
X847500D01*
G01X756541Y1762541D02*
X758000Y1764000D01*
G01X752910Y1758910D02*
X754370Y1760370D01*
G01X749280Y1755280D02*
X750739Y1756739D01*
G01X758000Y1764000D02*
X847500D01*
G01X758498Y1762799D02*
X847998D01*
G01X756541Y1762541D02*
X758000Y1764000D01*
G01X752910Y1758910D02*
X754370Y1760370D01*
G01X749280Y1755280D02*
X750739Y1756739D01*
G01X753199Y1775500D02*
X704699Y1727000D01*
G01X752701Y1776701D02*
X704201Y1728201D01*
G01X840699Y1775500D02*
X753199D01*
G01X840201Y1776701D02*
X752701D01*
G01X834985Y234214D02*
X842056Y227143D01*
G01X831354Y237845D02*
X832814Y236385D01*
G01X834985Y234214D02*
X842056Y227143D01*
G01X831354Y237845D02*
X832814Y236385D01*
G01X837663Y1002801D02*
X839727D01*
G01X826247D02*
X834593D01*
G01X821113D02*
X823177D01*
G01X815979D02*
X818043D01*
G01X837663D02*
X839727D01*
G01X826247D02*
X834593D01*
G01X821113D02*
X823177D01*
G01X815979D02*
X818043D01*
G01X837663D02*
X839727D01*
G01X826247D02*
X834593D01*
G01X821113D02*
X823177D01*
G01X815979D02*
X818043D01*
G01X837663D02*
X839727D01*
G01X826247D02*
X834593D01*
G01X821113D02*
X823177D01*
G01X815979D02*
X818043D01*
G01X810002Y1402500D02*
X807938D01*
G01X823072D02*
X813072D01*
G01X828206D02*
X826142D01*
G01X833340D02*
X831276D01*
G01X848338D02*
X836410D01*
G01X810002D02*
X807938D01*
G01X823072D02*
X813072D01*
G01X828206D02*
X826142D01*
G01X833340D02*
X831276D01*
G01X848338D02*
X836410D01*
G01X810002D02*
X807938D01*
G01X823072D02*
X813072D01*
G01X828206D02*
X826142D01*
G01X833340D02*
X831276D01*
G01X848338D02*
X836410D01*
G01X810002D02*
X807938D01*
G01X823072D02*
X813072D01*
G01X828206D02*
X826142D01*
G01X833340D02*
X831276D01*
G01X848338D02*
X836410D01*
G01X903499Y184799D02*
X928201Y209501D01*
G01X909038Y192037D02*
X916109Y199108D01*
G01X908327Y192037D02*
X909038D01*
G01X903001Y186000D02*
X906867Y189866D01*
G01X863402Y184799D02*
X903499D01*
G01X883932Y186000D02*
X903001D01*
G01X878798D02*
X880862D01*
G01X863900D02*
X875728D01*
G01X862441Y187459D02*
X863900Y186000D01*
G01X858810Y191090D02*
X860270Y189630D01*
G01X855180Y194720D02*
X856639Y193261D01*
G01X903499Y184799D02*
X928201Y209501D01*
G01X903499Y184799D02*
X928201Y209501D01*
G01X903499Y184799D02*
X928201Y209501D01*
G01X903499Y184799D02*
X928201Y209501D01*
G01X903499Y184799D02*
X928201Y209501D01*
G01X903499Y184799D02*
X928201Y209501D01*
G01X909038Y192037D02*
X916109Y199108D01*
G01X903499Y184799D02*
X928201Y209501D01*
G01X908327Y192037D02*
X909038D01*
G01X903499Y184799D02*
X928201Y209501D01*
G01X903001Y186000D02*
X906867Y189866D01*
G01X903499Y184799D02*
X928201Y209501D01*
G01X883932Y186000D02*
X903001D01*
G01X863402Y184799D02*
X903499D01*
G01X878798Y186000D02*
X880862D01*
G01X863402Y184799D02*
X903499D01*
G01X863900Y186000D02*
X875728D01*
G01X863402Y184799D02*
X903499D01*
G01X862441Y187459D02*
X863900Y186000D01*
G01X858810Y191090D02*
X860270Y189630D01*
G01X855180Y194720D02*
X856639Y193261D01*
G01X903499Y184799D02*
X928201Y209501D01*
G01X909038Y192037D02*
X916109Y199108D01*
G01X908327Y192037D02*
X909038D01*
G01X903001Y186000D02*
X906867Y189866D01*
G01X863402Y184799D02*
X903499D01*
G01X883932Y186000D02*
X903001D01*
G01X878798D02*
X880862D01*
G01X863900D02*
X875728D01*
G01X862441Y187459D02*
X863900Y186000D01*
G01X858810Y191090D02*
X860270Y189630D01*
G01X855180Y194720D02*
X856639Y193261D01*
G01X903499Y184799D02*
X928201Y209501D01*
G01X903499Y184799D02*
X928201Y209501D01*
G01X903499Y184799D02*
X928201Y209501D01*
G01X903499Y184799D02*
X928201Y209501D01*
G01X903499Y184799D02*
X928201Y209501D01*
G01X903499Y184799D02*
X928201Y209501D01*
G01X909038Y192037D02*
X916109Y199108D01*
G01X903499Y184799D02*
X928201Y209501D01*
G01X908327Y192037D02*
X909038D01*
G01X903499Y184799D02*
X928201Y209501D01*
G01X903001Y186000D02*
X906867Y189866D01*
G01X903499Y184799D02*
X928201Y209501D01*
G01X883932Y186000D02*
X903001D01*
G01X863402Y184799D02*
X903499D01*
G01X878798Y186000D02*
X880862D01*
G01X863402Y184799D02*
X903499D01*
G01X863900Y186000D02*
X875728D01*
G01X863402Y184799D02*
X903499D01*
G01X862441Y187459D02*
X863900Y186000D01*
G01X858810Y191090D02*
X860270Y189630D01*
G01X855180Y194720D02*
X856639Y193261D01*
G01X877000Y217097D02*
X868440D01*
G01X877000Y215896D02*
X868441D01*
G01X877000D02*
X868441D01*
G01X877000Y217097D02*
X868440D01*
G01X877045Y226545D02*
X874541D01*
G01X877000Y225344D02*
X874540D01*
G01X877000D02*
X874540D01*
G01X877045Y226545D02*
X874541D01*
G01X845938Y203962D02*
X853009Y196891D01*
G01X842308Y207592D02*
X843767Y206133D01*
G01X905248Y239399D02*
X900356D01*
G01X905746Y240600D02*
X900619D01*
G01X906145Y238502D02*
X905248Y239399D01*
G01X907346Y239000D02*
X905746Y240600D01*
G01X906145Y236393D02*
Y238502D01*
G01X907346Y236394D02*
Y239000D01*
G01X845938Y203962D02*
X853009Y196891D01*
G01X842308Y207592D02*
X843767Y206133D01*
G01X905746Y240600D02*
X900619D01*
G01X905248Y239399D02*
X900356D01*
G01X907346Y239000D02*
X905746Y240600D01*
G01X906145Y238502D02*
X905248Y239399D01*
G01X907346Y236394D02*
Y239000D01*
G01X906145Y236393D02*
Y238502D01*
G01X845938Y203962D02*
X853009Y196891D01*
G01X842308Y207592D02*
X843767Y206133D01*
G01X905248Y239399D02*
X900356D01*
G01X905746Y240600D02*
X900619D01*
G01X906145Y238502D02*
X905248Y239399D01*
G01X907346Y239000D02*
X905746Y240600D01*
G01X906145Y236393D02*
Y238502D01*
G01X907346Y236394D02*
Y239000D01*
G01X845938Y203962D02*
X853009Y196891D01*
G01X842308Y207592D02*
X843767Y206133D01*
G01X905746Y240600D02*
X900619D01*
G01X905248Y239399D02*
X900356D01*
G01X907346Y239000D02*
X905746Y240600D01*
G01X906145Y238502D02*
X905248Y239399D01*
G01X907346Y236394D02*
Y239000D01*
G01X906145Y236393D02*
Y238502D01*
G01X861001Y206499D02*
X877447D01*
G01X861499Y207700D02*
X877553D01*
G01X851487Y217712D02*
X861499Y207700D01*
G01X847857Y221342D02*
X849316Y219883D01*
G01X844227Y224972D02*
X845686Y223513D01*
G01X861499Y207700D02*
X877553D01*
G01X861001Y206499D02*
X877447D01*
G01X851487Y217712D02*
X861499Y207700D01*
G01X847857Y221342D02*
X849316Y219883D01*
G01X844227Y224972D02*
X845686Y223513D01*
G01X877000Y217097D02*
X868440D01*
G01X877000Y215896D02*
X868441D01*
G01X877000D02*
X868441D01*
G01X877000Y217097D02*
X868440D01*
G01X877500Y305286D02*
X868440D01*
G01X877525Y304085D02*
X868441D01*
G01X877525D02*
X868441D01*
G01X877500Y305286D02*
X868440D01*
G01X877500Y286388D02*
X868440D01*
G01X877500Y285187D02*
X868441D01*
G01X877500D02*
X868441D01*
G01X877500Y286388D02*
X868440D01*
G01X877526Y267490D02*
X868441D01*
G01X877500Y266289D02*
X868440D01*
G01X877500Y314734D02*
X874541D01*
G01X877526Y313533D02*
X874540D01*
G01X877526D02*
X874540D01*
G01X877500Y314734D02*
X874541D01*
G01X877500Y295837D02*
X874540D01*
G01X877525Y294636D02*
X874541D01*
G01X877525D02*
X874541D01*
G01X877500Y295837D02*
X874540D01*
G01X877526Y276939D02*
X874540D01*
G01X878025Y275738D02*
X874541D01*
G01X878025D02*
X874541D01*
G01X877526Y276939D02*
X874540D01*
G01X877500Y266289D02*
X868440D01*
G01X877526Y267490D02*
X868441D01*
G01X877500Y305286D02*
X868440D01*
G01X877525Y304085D02*
X868441D01*
G01X877525D02*
X868441D01*
G01X877500Y305286D02*
X868440D01*
G01X877500Y286388D02*
X868440D01*
G01X877500Y285187D02*
X868441D01*
G01X877500D02*
X868441D01*
G01X877500Y286388D02*
X868440D01*
G01X877526Y267490D02*
X868441D01*
G01X877500Y266289D02*
X868440D01*
G01X877500D02*
X868440D01*
G01X877526Y267490D02*
X868441D01*
G01X902123Y590924D02*
X928000Y616801D01*
G01X908837Y599337D02*
X915908Y606408D01*
G01X901625Y592125D02*
X906666Y597166D01*
G01X895143Y590924D02*
X902123D01*
G01X894645Y592125D02*
X901625D01*
G01X894018Y589799D02*
X895143Y590924D01*
G01X893520Y591000D02*
X894645Y592125D01*
G01X886122Y591000D02*
X893520D01*
G01X880988D02*
X883052D01*
G01X902123Y590924D02*
X928000Y616801D01*
G01X902123Y590924D02*
X928000Y616801D01*
G01X902123Y590924D02*
X928000Y616801D01*
G01X908837Y599337D02*
X915908Y606408D01*
G01X902123Y590924D02*
X928000Y616801D01*
G01X901625Y592125D02*
X906666Y597166D01*
G01X902123Y590924D02*
X928000Y616801D01*
G01X894645Y592125D02*
X901625D01*
G01X895143Y590924D02*
X902123D01*
G01X893520Y591000D02*
X894645Y592125D01*
G01X894018Y589799D02*
X895143Y590924D01*
G01X886122Y591000D02*
X893520D01*
G01X880988D02*
X883052D01*
G01X877500Y622609D02*
X868440D01*
G01X877525Y621408D02*
X868441D01*
G01X877525D02*
X868441D01*
G01X877500Y622609D02*
X868440D01*
G01X902123Y590924D02*
X928000Y616801D01*
G01X908837Y599337D02*
X915908Y606408D01*
G01X901625Y592125D02*
X906666Y597166D01*
G01X895143Y590924D02*
X902123D01*
G01X894645Y592125D02*
X901625D01*
G01X894018Y589799D02*
X895143Y590924D01*
G01X893520Y591000D02*
X894645Y592125D01*
G01X886122Y591000D02*
X893520D01*
G01X880988D02*
X883052D01*
G01X902123Y590924D02*
X928000Y616801D01*
G01X902123Y590924D02*
X928000Y616801D01*
G01X902123Y590924D02*
X928000Y616801D01*
G01X908837Y599337D02*
X915908Y606408D01*
G01X902123Y590924D02*
X928000Y616801D01*
G01X901625Y592125D02*
X906666Y597166D01*
G01X902123Y590924D02*
X928000Y616801D01*
G01X894645Y592125D02*
X901625D01*
G01X895143Y590924D02*
X902123D01*
G01X893520Y591000D02*
X894645Y592125D01*
G01X894018Y589799D02*
X895143Y590924D01*
G01X886122Y591000D02*
X893520D01*
G01X880988D02*
X883052D01*
G01X877500Y622609D02*
X868440D01*
G01X877525Y621408D02*
X868441D01*
G01X877525D02*
X868441D01*
G01X877500Y622609D02*
X868440D01*
G01X877526Y691900D02*
X868440D01*
G01X877525Y690699D02*
X868441D01*
G01X877525D02*
X868441D01*
G01X877526Y691900D02*
X868440D01*
G01X877526Y673002D02*
X868441D01*
G01X877500Y671801D02*
X868440D01*
G01X877500D02*
X868440D01*
G01X877526Y673002D02*
X868441D01*
G01X877526Y701349D02*
X874540D01*
G01X877525Y700148D02*
X874541D01*
G01X877525D02*
X874541D01*
G01X877526Y701349D02*
X874540D01*
G01X877526Y682451D02*
X874540D01*
G01X877500Y681250D02*
X874541D01*
G01X877500D02*
X874541D01*
G01X877526Y682451D02*
X874540D01*
G01X877500Y632057D02*
X874541D01*
G01X877500Y630856D02*
X874540D01*
G01X906145Y644014D02*
Y641905D01*
G01X907346Y644512D02*
Y641906D01*
G01X905129Y645030D02*
X906145Y644014D01*
G01X905627Y646231D02*
X907346Y644512D01*
G01X900475Y645030D02*
X905129D01*
G01X900500Y646231D02*
X905627D01*
G01X907346Y644512D02*
Y641906D01*
G01X906145Y644014D02*
Y641905D01*
G01X905627Y646231D02*
X907346Y644512D01*
G01X905129Y645030D02*
X906145Y644014D01*
G01X900500Y646231D02*
X905627D01*
G01X900475Y645030D02*
X905129D01*
G01X877500Y630856D02*
X874540D01*
G01X877500Y632057D02*
X874541D01*
G01X906145Y644014D02*
Y641905D01*
G01X907346Y644512D02*
Y641906D01*
G01X905129Y645030D02*
X906145Y644014D01*
G01X905627Y646231D02*
X907346Y644512D01*
G01X900475Y645030D02*
X905129D01*
G01X900500Y646231D02*
X905627D01*
G01X907346Y644512D02*
Y641906D01*
G01X906145Y644014D02*
Y641905D01*
G01X905627Y646231D02*
X907346Y644512D01*
G01X905129Y645030D02*
X906145Y644014D01*
G01X900500Y646231D02*
X905627D01*
G01X900475Y645030D02*
X905129D01*
G01X877526Y691900D02*
X868440D01*
G01X877525Y690699D02*
X868441D01*
G01X877525D02*
X868441D01*
G01X877526Y691900D02*
X868440D01*
G01X877526Y673002D02*
X868441D01*
G01X877500Y671801D02*
X868440D01*
G01X877500D02*
X868440D01*
G01X877526Y673002D02*
X868441D01*
G01X877526Y710798D02*
X868440D01*
G01X877525Y709597D02*
X868441D01*
G01X877525D02*
X868441D01*
G01X877526Y710798D02*
X868440D01*
G01X877500Y720246D02*
X874541D01*
G01X877526Y719045D02*
X874540D01*
G01X877526D02*
X874540D01*
G01X877500Y720246D02*
X874541D01*
G01X877526Y710798D02*
X868440D01*
G01X877525Y709597D02*
X868441D01*
G01X877525D02*
X868441D01*
G01X877526Y710798D02*
X868440D01*
G01X877500Y1028121D02*
X868440D01*
G01X877500Y1026920D02*
X868441D01*
G01X877500D02*
X868441D01*
G01X877500Y1028121D02*
X868440D01*
G01X877500Y1037569D02*
X874541D01*
G01X877500Y1036368D02*
X874540D01*
G01X877500D02*
X874540D01*
G01X877500Y1037569D02*
X874541D01*
G01X904599Y995799D02*
X928000Y1019200D01*
G01X904101Y997000D02*
X909768Y1002667D01*
G01X873502Y995799D02*
X904599D01*
G01X874000Y997000D02*
X904101D01*
G01X867701Y1001600D02*
X873502Y995799D01*
G01X868199Y1002801D02*
X874000Y997000D01*
G01X866135Y1002801D02*
X868199D01*
G01X861001D02*
X863065D01*
G01X855867D02*
X857931D01*
G01X842797D02*
X852797D01*
G01X905272Y1050399D02*
X900332D01*
G01X905770Y1051600D02*
X900643D01*
G01X906145Y1049526D02*
X905272Y1050399D01*
G01X907346Y1050024D02*
X905770Y1051600D01*
G01X906145Y1047417D02*
Y1049526D01*
G01X907346Y1047418D02*
Y1050024D01*
G01X904599Y995799D02*
X928000Y1019200D01*
G01X904599Y995799D02*
X928000Y1019200D01*
G01X904599Y995799D02*
X928000Y1019200D01*
G01X904101Y997000D02*
X909768Y1002667D01*
G01X904599Y995799D02*
X928000Y1019200D01*
G01X874000Y997000D02*
X904101D01*
G01X873502Y995799D02*
X904599D01*
G01X868199Y1002801D02*
X874000Y997000D01*
G01X867701Y1001600D02*
X873502Y995799D01*
G01X866135Y1002801D02*
X868199D01*
G01X861001D02*
X863065D01*
G01X855867D02*
X857931D01*
G01X842797D02*
X852797D01*
G01X905770Y1051600D02*
X900643D01*
G01X905272Y1050399D02*
X900332D01*
G01X907346Y1050024D02*
X905770Y1051600D01*
G01X906145Y1049526D02*
X905272Y1050399D01*
G01X907346Y1047418D02*
Y1050024D01*
G01X906145Y1047417D02*
Y1049526D01*
G01X904599Y995799D02*
X928000Y1019200D01*
G01X904101Y997000D02*
X909768Y1002667D01*
G01X873502Y995799D02*
X904599D01*
G01X874000Y997000D02*
X904101D01*
G01X867701Y1001600D02*
X873502Y995799D01*
G01X868199Y1002801D02*
X874000Y997000D01*
G01X866135Y1002801D02*
X868199D01*
G01X861001D02*
X863065D01*
G01X855867D02*
X857931D01*
G01X842797D02*
X852797D01*
G01X905272Y1050399D02*
X900332D01*
G01X905770Y1051600D02*
X900643D01*
G01X906145Y1049526D02*
X905272Y1050399D01*
G01X907346Y1050024D02*
X905770Y1051600D01*
G01X906145Y1047417D02*
Y1049526D01*
G01X907346Y1047418D02*
Y1050024D01*
G01X904599Y995799D02*
X928000Y1019200D01*
G01X904599Y995799D02*
X928000Y1019200D01*
G01X904599Y995799D02*
X928000Y1019200D01*
G01X904101Y997000D02*
X909768Y1002667D01*
G01X904599Y995799D02*
X928000Y1019200D01*
G01X874000Y997000D02*
X904101D01*
G01X873502Y995799D02*
X904599D01*
G01X868199Y1002801D02*
X874000Y997000D01*
G01X867701Y1001600D02*
X873502Y995799D01*
G01X866135Y1002801D02*
X868199D01*
G01X861001D02*
X863065D01*
G01X855867D02*
X857931D01*
G01X842797D02*
X852797D01*
G01X905770Y1051600D02*
X900643D01*
G01X905272Y1050399D02*
X900332D01*
G01X907346Y1050024D02*
X905770Y1051600D01*
G01X906145Y1049526D02*
X905272Y1050399D01*
G01X907346Y1047418D02*
Y1050024D01*
G01X906145Y1047417D02*
Y1049526D01*
G01X871801Y1018671D02*
X877500D01*
G01X866667D02*
X868731D01*
G01X861533D02*
X863597D01*
G01X848463D02*
X858463D01*
G01X843329D02*
X845393D01*
G01X871801D02*
X877500D01*
G01X866667D02*
X868731D01*
G01X861533D02*
X863597D01*
G01X848463D02*
X858463D01*
G01X843329D02*
X845393D01*
G01X877500Y1028121D02*
X868440D01*
G01X877500Y1026920D02*
X868441D01*
G01X877500D02*
X868441D01*
G01X877500Y1028121D02*
X868440D01*
G01X877500Y1116310D02*
X868440D01*
G01X877525Y1115109D02*
X868441D01*
G01X877525D02*
X868441D01*
G01X877500Y1116310D02*
X868440D01*
G01X877500Y1097412D02*
X868440D01*
G01X877525Y1096211D02*
X868441D01*
G01X877525D02*
X868441D01*
G01X877500Y1097412D02*
X868440D01*
G01X877526Y1078514D02*
X868441D01*
G01X877500Y1077313D02*
X868440D01*
G01X877500D02*
X868440D01*
G01X877526Y1078514D02*
X868441D01*
G01X877500Y1125758D02*
X874541D01*
G01X877526Y1124557D02*
X874540D01*
G01X877526D02*
X874540D01*
G01X877500Y1125758D02*
X874541D01*
G01X877500Y1106861D02*
X874540D01*
G01X877525Y1105660D02*
X874541D01*
G01X877525D02*
X874541D01*
G01X877500Y1106861D02*
X874540D01*
G01X877526Y1087963D02*
X874540D01*
G01X877525Y1086762D02*
X874541D01*
G01X877525D02*
X874541D01*
G01X877526Y1087963D02*
X874540D01*
G01X877500Y1116310D02*
X868440D01*
G01X877525Y1115109D02*
X868441D01*
G01X877525D02*
X868441D01*
G01X877500Y1116310D02*
X868440D01*
G01X877500Y1097412D02*
X868440D01*
G01X877525Y1096211D02*
X868441D01*
G01X877525D02*
X868441D01*
G01X877500Y1097412D02*
X868440D01*
G01X877526Y1078514D02*
X868441D01*
G01X877500Y1077313D02*
X868440D01*
G01X877500D02*
X868440D01*
G01X877526Y1078514D02*
X868441D01*
G01X853472Y1402500D02*
X851408D01*
G01X866542D02*
X856542D01*
G01X871676D02*
X869612D01*
G01X876810D02*
X874746D01*
G01X903301D02*
X879880D01*
G01X928000Y1425500D02*
X903799Y1401299D01*
G01X926799Y1425998D02*
X903301Y1402500D01*
G01X853472D02*
X851408D01*
G01X866542D02*
X856542D01*
G01X871676D02*
X869612D01*
G01X876810D02*
X874746D01*
G01X903301D02*
X879880D01*
G01X926799Y1425998D02*
X903301Y1402500D01*
G01X928000Y1425500D02*
X903799Y1401299D01*
G01X853472Y1402500D02*
X851408D01*
G01X866542D02*
X856542D01*
G01X871676D02*
X869612D01*
G01X876810D02*
X874746D01*
G01X903301D02*
X879880D01*
G01X928000Y1425500D02*
X903799Y1401299D01*
G01X926799Y1425998D02*
X903301Y1402500D01*
G01X853472D02*
X851408D01*
G01X866542D02*
X856542D01*
G01X871676D02*
X869612D01*
G01X876810D02*
X874746D01*
G01X903301D02*
X879880D01*
G01X926799Y1425998D02*
X903301Y1402500D01*
G01X928000Y1425500D02*
X903799Y1401299D01*
G01X877525Y1501723D02*
X868441D01*
G01X877525D02*
X868441D01*
G01X877500Y1484026D02*
X868441D01*
G01X877500Y1482825D02*
X868440D01*
G01X877500D02*
X868440D01*
G01X877500Y1484026D02*
X868441D01*
G01X877500Y1433633D02*
X868440D01*
G01X877500Y1432432D02*
X868441D01*
G01X877500D02*
X868441D01*
G01X877500Y1433633D02*
X868440D01*
G01X877526Y1493475D02*
X874540D01*
G01X877525Y1492274D02*
X874541D01*
G01X877525D02*
X874541D01*
G01X877526Y1493475D02*
X874540D01*
G01X877500Y1443081D02*
X874541D01*
G01X877526Y1441880D02*
X874540D01*
G01X877526D02*
X874540D01*
G01X877500Y1443081D02*
X874541D01*
G01X905084Y1456099D02*
X900520D01*
G01X905582Y1457300D02*
X900455D01*
G01X906145Y1455038D02*
X905084Y1456099D01*
G01X907346Y1455536D02*
X905582Y1457300D01*
G01X906145Y1452929D02*
Y1455038D01*
G01X907346Y1452930D02*
Y1455536D01*
G01X905582Y1457300D02*
X900455D01*
G01X905084Y1456099D02*
X900520D01*
G01X907346Y1455536D02*
X905582Y1457300D01*
G01X906145Y1455038D02*
X905084Y1456099D01*
G01X907346Y1452930D02*
Y1455536D01*
G01X906145Y1452929D02*
Y1455038D01*
G01X905084Y1456099D02*
X900520D01*
G01X905582Y1457300D02*
X900455D01*
G01X906145Y1455038D02*
X905084Y1456099D01*
G01X907346Y1455536D02*
X905582Y1457300D01*
G01X906145Y1452929D02*
Y1455038D01*
G01X907346Y1452930D02*
Y1455536D01*
G01X905582Y1457300D02*
X900455D01*
G01X905084Y1456099D02*
X900520D01*
G01X907346Y1455536D02*
X905582Y1457300D01*
G01X906145Y1455038D02*
X905084Y1456099D01*
G01X907346Y1452930D02*
Y1455536D01*
G01X906145Y1452929D02*
Y1455038D01*
G01X877525Y1501723D02*
X868441D01*
G01X877525D02*
X868441D01*
G01X877500Y1484026D02*
X868441D01*
G01X877500Y1482825D02*
X868440D01*
G01X877500D02*
X868440D01*
G01X877500Y1484026D02*
X868441D01*
G01X877500Y1433633D02*
X868440D01*
G01X877500Y1432432D02*
X868441D01*
G01X877500D02*
X868441D01*
G01X877500Y1433633D02*
X868440D01*
G01X877500Y1521822D02*
X868440D01*
G01X877525Y1520621D02*
X868441D01*
G01X877525D02*
X868441D01*
G01X877500Y1521822D02*
X868440D01*
G01X877500Y1502924D02*
X868440D01*
G01X877500Y1531270D02*
X874541D01*
G01X877526Y1530069D02*
X874540D01*
G01X877526D02*
X874540D01*
G01X877500Y1531270D02*
X874541D01*
G01X877526Y1512373D02*
X874540D01*
G01X877525Y1511172D02*
X874541D01*
G01X877525D02*
X874541D01*
G01X877526Y1512373D02*
X874540D01*
G01X877500Y1502924D02*
X868440D01*
G01X877500Y1521822D02*
X868440D01*
G01X877525Y1520621D02*
X868441D01*
G01X877525D02*
X868441D01*
G01X877500Y1521822D02*
X868440D01*
G01X877500Y1502924D02*
X868440D01*
G01X877500D02*
X868440D01*
G01X847998Y1762799D02*
X891726Y1806527D01*
G01X847500Y1764000D02*
X891228Y1807728D01*
G01X847500Y1764000D02*
X891228Y1807728D01*
G01X847998Y1762799D02*
X891726Y1806527D01*
G01X863799Y1800299D02*
X840201Y1776701D01*
G01X865000Y1799801D02*
X840699Y1775500D01*
G01X847998Y1762799D02*
X891726Y1806527D01*
G01X847500Y1764000D02*
X891228Y1807728D01*
G01X847500Y1764000D02*
X891228Y1807728D01*
G01X847998Y1762799D02*
X891726Y1806527D01*
G01X865000Y1799801D02*
X840699Y1775500D01*
G01X863799Y1800299D02*
X840201Y1776701D01*
G01X877500Y1839145D02*
X868440D01*
G01X877500Y1837944D02*
X868441D01*
G01X877500D02*
X868441D01*
G01X877500Y1839145D02*
X868440D01*
G01X877593Y1848593D02*
X874541D01*
G01X877500Y1847392D02*
X874540D01*
G01X877500D02*
X874540D01*
G01X877593Y1848593D02*
X874541D01*
G01X908527Y1806527D02*
X928000Y1826000D01*
G01X908029Y1807728D02*
X915908Y1815607D01*
G01X891726Y1806527D02*
X908527D01*
G01X891228Y1807728D02*
X908029D01*
G01X906145Y1860550D02*
Y1858441D01*
G01X907346Y1861048D02*
Y1858442D01*
G01X905129Y1861566D02*
X906145Y1860550D01*
G01X905627Y1862767D02*
X907346Y1861048D01*
G01X900475Y1861566D02*
X905129D01*
G01X900500Y1862767D02*
X905627D01*
G01X908527Y1806527D02*
X928000Y1826000D01*
G01X908527Y1806527D02*
X928000Y1826000D01*
G01X908527Y1806527D02*
X928000Y1826000D01*
G01X908029Y1807728D02*
X915908Y1815607D01*
G01X908527Y1806527D02*
X928000Y1826000D01*
G01X891228Y1807728D02*
X908029D01*
G01X891726Y1806527D02*
X908527D01*
G01X907346Y1861048D02*
Y1858442D01*
G01X906145Y1860550D02*
Y1858441D01*
G01X905627Y1862767D02*
X907346Y1861048D01*
G01X905129Y1861566D02*
X906145Y1860550D01*
G01X900500Y1862767D02*
X905627D01*
G01X900475Y1861566D02*
X905129D01*
G01X863799Y1821498D02*
Y1800299D01*
G01X865000Y1821000D02*
Y1799801D01*
G01X871996Y1829695D02*
X863799Y1821498D01*
G01X872494Y1828494D02*
X865000Y1821000D01*
G01X877109Y1829695D02*
X871996D01*
G01X877109Y1828494D02*
X872494D01*
G01X908527Y1806527D02*
X928000Y1826000D01*
G01X908029Y1807728D02*
X915908Y1815607D01*
G01X891726Y1806527D02*
X908527D01*
G01X891228Y1807728D02*
X908029D01*
G01X906145Y1860550D02*
Y1858441D01*
G01X907346Y1861048D02*
Y1858442D01*
G01X905129Y1861566D02*
X906145Y1860550D01*
G01X905627Y1862767D02*
X907346Y1861048D01*
G01X900475Y1861566D02*
X905129D01*
G01X900500Y1862767D02*
X905627D01*
G01X908527Y1806527D02*
X928000Y1826000D01*
G01X908527Y1806527D02*
X928000Y1826000D01*
G01X908527Y1806527D02*
X928000Y1826000D01*
G01X908029Y1807728D02*
X915908Y1815607D01*
G01X908527Y1806527D02*
X928000Y1826000D01*
G01X891228Y1807728D02*
X908029D01*
G01X891726Y1806527D02*
X908527D01*
G01X907346Y1861048D02*
Y1858442D01*
G01X906145Y1860550D02*
Y1858441D01*
G01X905627Y1862767D02*
X907346Y1861048D01*
G01X905129Y1861566D02*
X906145Y1860550D01*
G01X900500Y1862767D02*
X905627D01*
G01X900475Y1861566D02*
X905129D01*
G01X865000Y1821000D02*
Y1799801D01*
G01X863799Y1821498D02*
Y1800299D01*
G01X872494Y1828494D02*
X865000Y1821000D01*
G01X871996Y1829695D02*
X863799Y1821498D01*
G01X877109Y1828494D02*
X872494D01*
G01X877109Y1829695D02*
X871996D01*
G01X877500Y1839145D02*
X868440D01*
G01X877500Y1837944D02*
X868441D01*
G01X877500D02*
X868441D01*
G01X877500Y1839145D02*
X868440D01*
G01X877526Y1927334D02*
X868440D01*
G01X877525Y1926133D02*
X868441D01*
G01X877525D02*
X868441D01*
G01X877526Y1927334D02*
X868440D01*
G01X877526Y1908436D02*
X868440D01*
G01X877500Y1907235D02*
X868441D01*
G01X877500D02*
X868441D01*
G01X877526Y1908436D02*
X868440D01*
G01X877500Y1889538D02*
X868441D01*
G01X877526Y1888337D02*
X868440D01*
G01X877526D02*
X868440D01*
G01X877500Y1889538D02*
X868441D01*
G01X877526Y1936782D02*
X874541D01*
G01X877526Y1935581D02*
X874540D01*
G01X877526D02*
X874540D01*
G01X877526Y1936782D02*
X874541D01*
G01X877185Y1917885D02*
X874470D01*
G01X877316Y1916684D02*
X874541D01*
G01X877316D02*
X874541D01*
G01X877185Y1917885D02*
X874470D01*
G01X877526Y1898987D02*
X874540D01*
G01X877525Y1897786D02*
X874541D01*
G01X877525D02*
X874541D01*
G01X877526Y1898987D02*
X874540D01*
G01X877526Y1927334D02*
X868440D01*
G01X877525Y1926133D02*
X868441D01*
G01X877525D02*
X868441D01*
G01X877526Y1927334D02*
X868440D01*
G01X877526Y1908436D02*
X868440D01*
G01X877500Y1907235D02*
X868441D01*
G01X877500D02*
X868441D01*
G01X877526Y1908436D02*
X868440D01*
G01X877500Y1889538D02*
X868441D01*
G01X877526Y1888337D02*
X868440D01*
G01X877526D02*
X868440D01*
G01X877500Y1889538D02*
X868441D01*
G01X924950Y240701D02*
X919846D01*
G01X924452Y239500D02*
X919845D01*
G01X928201Y237450D02*
X924950Y240701D01*
G01X927000Y236952D02*
X924452Y239500D01*
G01X928201Y209501D02*
Y237450D01*
G01X927000Y234888D02*
Y236952D01*
G01Y229754D02*
Y231818D01*
G01Y224620D02*
Y226684D01*
G01Y209999D02*
Y221550D01*
G01X925541Y208540D02*
X927000Y209999D01*
G01X924829Y208540D02*
X925541D01*
G01X921910Y204909D02*
X923370Y206369D01*
G01X921199Y204909D02*
X921910D01*
G01X918280Y201279D02*
X919739Y202738D01*
G01X917569Y201279D02*
X918280D01*
G01X924452Y239500D02*
X919845D01*
G01X924950Y240701D02*
X919846D01*
G01X927000Y236952D02*
X924452Y239500D01*
G01X928201Y237450D02*
X924950Y240701D01*
G01X927000Y234888D02*
Y236952D01*
G01X928201Y209501D02*
Y237450D01*
G01X927000Y229754D02*
Y231818D01*
G01X928201Y209501D02*
Y237450D01*
G01X927000Y224620D02*
Y226684D01*
G01X928201Y209501D02*
Y237450D01*
G01X927000Y209999D02*
Y221550D01*
G01X928201Y209501D02*
Y237450D01*
G01X925541Y208540D02*
X927000Y209999D01*
G01X924829Y208540D02*
X925541D01*
G01X921910Y204909D02*
X923370Y206369D01*
G01X921199Y204909D02*
X921910D01*
G01X918280Y201279D02*
X919739Y202738D01*
G01X917569Y201279D02*
X918280D01*
G01X924950Y240701D02*
X919846D01*
G01X924452Y239500D02*
X919845D01*
G01X928201Y237450D02*
X924950Y240701D01*
G01X927000Y236952D02*
X924452Y239500D01*
G01X928201Y209501D02*
Y237450D01*
G01X927000Y234888D02*
Y236952D01*
G01Y229754D02*
Y231818D01*
G01Y224620D02*
Y226684D01*
G01Y209999D02*
Y221550D01*
G01X925541Y208540D02*
X927000Y209999D01*
G01X924829Y208540D02*
X925541D01*
G01X921910Y204909D02*
X923370Y206369D01*
G01X921199Y204909D02*
X921910D01*
G01X918280Y201279D02*
X919739Y202738D01*
G01X917569Y201279D02*
X918280D01*
G01X924452Y239500D02*
X919845D01*
G01X924950Y240701D02*
X919846D01*
G01X927000Y236952D02*
X924452Y239500D01*
G01X928201Y237450D02*
X924950Y240701D01*
G01X927000Y234888D02*
Y236952D01*
G01X928201Y209501D02*
Y237450D01*
G01X927000Y229754D02*
Y231818D01*
G01X928201Y209501D02*
Y237450D01*
G01X927000Y224620D02*
Y226684D01*
G01X928201Y209501D02*
Y237450D01*
G01X927000Y209999D02*
Y221550D01*
G01X928201Y209501D02*
Y237450D01*
G01X925541Y208540D02*
X927000Y209999D01*
G01X924829Y208540D02*
X925541D01*
G01X921910Y204909D02*
X923370Y206369D01*
G01X921199Y204909D02*
X921910D01*
G01X918280Y201279D02*
X919739Y202738D01*
G01X917569Y201279D02*
X918280D01*
G01X928000Y616801D02*
Y643163D01*
G01X926799Y629069D02*
Y631133D01*
G01Y617299D02*
Y625999D01*
G01X925340Y615840D02*
X926799Y617299D01*
G01X921709Y612209D02*
X923169Y613669D01*
G01X918079Y608579D02*
X919538Y610038D01*
G01X928000Y616801D02*
Y643163D01*
G01Y616801D02*
Y643163D01*
G01X926799Y629069D02*
Y631133D01*
G01X928000Y616801D02*
Y643163D01*
G01X926799Y617299D02*
Y625999D01*
G01X928000Y616801D02*
Y643163D01*
G01X925340Y615840D02*
X926799Y617299D01*
G01X921709Y612209D02*
X923169Y613669D01*
G01X918079Y608579D02*
X919538Y610038D01*
G01X928000Y616801D02*
Y643163D01*
G01X926799Y629069D02*
Y631133D01*
G01Y617299D02*
Y625999D01*
G01X925340Y615840D02*
X926799Y617299D01*
G01X921709Y612209D02*
X923169Y613669D01*
G01X918079Y608579D02*
X919538Y610038D01*
G01X928000Y616801D02*
Y643163D01*
G01Y616801D02*
Y643163D01*
G01X926799Y629069D02*
Y631133D01*
G01X928000Y616801D02*
Y643163D01*
G01X926799Y617299D02*
Y625999D01*
G01X928000Y616801D02*
Y643163D01*
G01X925340Y615840D02*
X926799Y617299D01*
G01X921709Y612209D02*
X923169Y613669D01*
G01X918079Y608579D02*
X919538Y610038D01*
G01X924950Y646213D02*
X919846D01*
G01X924452Y645012D02*
X919845D01*
G01X928000Y643163D02*
X924950Y646213D01*
G01X926799Y642665D02*
X924452Y645012D01*
G01X926799Y639337D02*
Y642665D01*
G01Y634203D02*
Y636267D01*
G01X924452Y645012D02*
X919845D01*
G01X924950Y646213D02*
X919846D01*
G01X926799Y642665D02*
X924452Y645012D01*
G01X928000Y643163D02*
X924950Y646213D01*
G01X926799Y639337D02*
Y642665D01*
G01Y634203D02*
Y636267D01*
G01X924950Y646213D02*
X919846D01*
G01X924452Y645012D02*
X919845D01*
G01X928000Y643163D02*
X924950Y646213D01*
G01X926799Y642665D02*
X924452Y645012D01*
G01X926799Y639337D02*
Y642665D01*
G01Y634203D02*
Y636267D01*
G01X924452Y645012D02*
X919845D01*
G01X924950Y646213D02*
X919846D01*
G01X926799Y642665D02*
X924452Y645012D01*
G01X928000Y643163D02*
X924950Y646213D01*
G01X926799Y639337D02*
Y642665D01*
G01Y634203D02*
Y636267D01*
G01X924950Y1051725D02*
X919846D01*
G01X924452Y1050524D02*
X919845D01*
G01X928000Y1048675D02*
X924950Y1051725D01*
G01X926799Y1048177D02*
X924452Y1050524D01*
G01X928000Y1019200D02*
Y1048675D01*
G01X926799Y1040770D02*
Y1048177D01*
G01Y1035636D02*
Y1037700D01*
G01Y1030502D02*
Y1032566D01*
G01Y1019698D02*
Y1027432D01*
G01X919199Y1012098D02*
X926799Y1019698D01*
G01X915569Y1008468D02*
X917028Y1009927D01*
G01X911939Y1004838D02*
X913398Y1006297D01*
G01X924452Y1050524D02*
X919845D01*
G01X924950Y1051725D02*
X919846D01*
G01X926799Y1048177D02*
X924452Y1050524D01*
G01X928000Y1048675D02*
X924950Y1051725D01*
G01X926799Y1040770D02*
Y1048177D01*
G01X928000Y1019200D02*
Y1048675D01*
G01X926799Y1035636D02*
Y1037700D01*
G01X928000Y1019200D02*
Y1048675D01*
G01X926799Y1030502D02*
Y1032566D01*
G01X928000Y1019200D02*
Y1048675D01*
G01X926799Y1019698D02*
Y1027432D01*
G01X928000Y1019200D02*
Y1048675D01*
G01X919199Y1012098D02*
X926799Y1019698D01*
G01X915569Y1008468D02*
X917028Y1009927D01*
G01X911939Y1004838D02*
X913398Y1006297D01*
G01X924950Y1051725D02*
X919846D01*
G01X924452Y1050524D02*
X919845D01*
G01X928000Y1048675D02*
X924950Y1051725D01*
G01X926799Y1048177D02*
X924452Y1050524D01*
G01X928000Y1019200D02*
Y1048675D01*
G01X926799Y1040770D02*
Y1048177D01*
G01Y1035636D02*
Y1037700D01*
G01Y1030502D02*
Y1032566D01*
G01Y1019698D02*
Y1027432D01*
G01X919199Y1012098D02*
X926799Y1019698D01*
G01X915569Y1008468D02*
X917028Y1009927D01*
G01X911939Y1004838D02*
X913398Y1006297D01*
G01X924452Y1050524D02*
X919845D01*
G01X924950Y1051725D02*
X919846D01*
G01X926799Y1048177D02*
X924452Y1050524D01*
G01X928000Y1048675D02*
X924950Y1051725D01*
G01X926799Y1040770D02*
Y1048177D01*
G01X928000Y1019200D02*
Y1048675D01*
G01X926799Y1035636D02*
Y1037700D01*
G01X928000Y1019200D02*
Y1048675D01*
G01X926799Y1030502D02*
Y1032566D01*
G01X928000Y1019200D02*
Y1048675D01*
G01X926799Y1019698D02*
Y1027432D01*
G01X928000Y1019200D02*
Y1048675D01*
G01X919199Y1012098D02*
X926799Y1019698D01*
G01X915569Y1008468D02*
X917028Y1009927D01*
G01X911939Y1004838D02*
X913398Y1006297D01*
G01X928000Y1454187D02*
Y1425500D01*
G01X926799Y1453689D02*
Y1425998D01*
G01Y1453689D02*
Y1425998D01*
G01X928000Y1454187D02*
Y1425500D01*
G01Y1454187D02*
Y1425500D01*
G01X926799Y1453689D02*
Y1425998D01*
G01Y1453689D02*
Y1425998D01*
G01X928000Y1454187D02*
Y1425500D01*
G01X924950Y1457237D02*
X928000Y1454187D01*
G01X924452Y1456036D02*
X926799Y1453689D01*
G01X919846Y1457237D02*
X924950D01*
G01X919845Y1456036D02*
X924452D01*
G01D02*
X926799Y1453689D01*
G01X924950Y1457237D02*
X928000Y1454187D01*
G01X919845Y1456036D02*
X924452D01*
G01X919846Y1457237D02*
X924950D01*
G01D02*
X928000Y1454187D01*
G01X924452Y1456036D02*
X926799Y1453689D01*
G01X919846Y1457237D02*
X924950D01*
G01X919845Y1456036D02*
X924452D01*
G01D02*
X926799Y1453689D01*
G01X924950Y1457237D02*
X928000Y1454187D01*
G01X919845Y1456036D02*
X924452D01*
G01X919846Y1457237D02*
X924950D01*
G01Y1862749D02*
X919846D01*
G01X924452Y1861548D02*
X919845D01*
G01X928000Y1859699D02*
X924950Y1862749D01*
G01X926799Y1859201D02*
X924452Y1861548D01*
G01X928000Y1826000D02*
Y1859699D01*
G01X926799Y1857137D02*
Y1859201D01*
G01Y1852003D02*
Y1854067D01*
G01Y1846869D02*
Y1848933D01*
G01Y1826498D02*
Y1843799D01*
G01X925340Y1825039D02*
X926799Y1826498D01*
G01X921709Y1821408D02*
X923169Y1822868D01*
G01X918079Y1817778D02*
X919538Y1819237D01*
G01X924452Y1861548D02*
X919845D01*
G01X924950Y1862749D02*
X919846D01*
G01X926799Y1859201D02*
X924452Y1861548D01*
G01X928000Y1859699D02*
X924950Y1862749D01*
G01X926799Y1857137D02*
Y1859201D01*
G01X928000Y1826000D02*
Y1859699D01*
G01X926799Y1852003D02*
Y1854067D01*
G01X928000Y1826000D02*
Y1859699D01*
G01X926799Y1846869D02*
Y1848933D01*
G01X928000Y1826000D02*
Y1859699D01*
G01X926799Y1826498D02*
Y1843799D01*
G01X928000Y1826000D02*
Y1859699D01*
G01X925340Y1825039D02*
X926799Y1826498D01*
G01X921709Y1821408D02*
X923169Y1822868D01*
G01X918079Y1817778D02*
X919538Y1819237D01*
G01X924950Y1862749D02*
X919846D01*
G01X924452Y1861548D02*
X919845D01*
G01X928000Y1859699D02*
X924950Y1862749D01*
G01X926799Y1859201D02*
X924452Y1861548D01*
G01X928000Y1826000D02*
Y1859699D01*
G01X926799Y1857137D02*
Y1859201D01*
G01Y1852003D02*
Y1854067D01*
G01Y1846869D02*
Y1848933D01*
G01Y1826498D02*
Y1843799D01*
G01X925340Y1825039D02*
X926799Y1826498D01*
G01X921709Y1821408D02*
X923169Y1822868D01*
G01X918079Y1817778D02*
X919538Y1819237D01*
G01X924452Y1861548D02*
X919845D01*
G01X924950Y1862749D02*
X919846D01*
G01X926799Y1859201D02*
X924452Y1861548D01*
G01X928000Y1859699D02*
X924950Y1862749D01*
G01X926799Y1857137D02*
Y1859201D01*
G01X928000Y1826000D02*
Y1859699D01*
G01X926799Y1852003D02*
Y1854067D01*
G01X928000Y1826000D02*
Y1859699D01*
G01X926799Y1846869D02*
Y1848933D01*
G01X928000Y1826000D02*
Y1859699D01*
G01X926799Y1826498D02*
Y1843799D01*
G01X928000Y1826000D02*
Y1859699D01*
G01X925340Y1825039D02*
X926799Y1826498D01*
G01X921709Y1821408D02*
X923169Y1822868D01*
G01X918079Y1817778D02*
X919538Y1819237D01*
M02*
